G04*
G04 #@! TF.GenerationSoftware,Altium Limited,Altium Designer,22.4.2 (48)*
G04*
G04 Layer_Color=2752767*
%FSLAX25Y25*%
%MOIN*%
G70*
G04*
G04 #@! TF.SameCoordinates,446674BB-F454-490D-8607-5140536C8ADF*
G04*
G04*
G04 #@! TF.FilePolarity,Positive*
G04*
G01*
G75*
%ADD182C,0.00200*%
%ADD183C,0.00267*%
%ADD184C,0.00133*%
D182*
X141562Y-120879D02*
Y-119279D01*
X143162D01*
Y-120879D01*
X141562D01*
X151562D02*
Y-119279D01*
X153162D01*
Y-120879D01*
X151562D01*
X161562D02*
Y-119279D01*
X163162D01*
Y-120879D01*
X161562D01*
X171562D02*
Y-119279D01*
X173162D01*
Y-120879D01*
X171562D01*
X674409Y-195288D02*
X673609Y-193688D01*
X675210D01*
X674409Y-195288D01*
X645669D02*
X646069Y-194888D01*
X646469D01*
X646069Y-194488D01*
X646469Y-194088D01*
X646069D01*
X645669Y-193688D01*
X645269Y-194088D01*
X644869D01*
X645269Y-194488D01*
X644869Y-194888D01*
X645269D01*
X645669Y-195288D01*
X624016D02*
X624416Y-194888D01*
X624816D01*
X624416Y-194488D01*
X624816Y-194088D01*
X624416D01*
X624016Y-193688D01*
X623616Y-194088D01*
X623216D01*
X623616Y-194488D01*
X623216Y-194888D01*
X623616D01*
X624016Y-195288D01*
Y-178753D02*
X624416Y-178353D01*
X624816D01*
X624416Y-177953D01*
X624816Y-177553D01*
X624416D01*
X624016Y-177153D01*
X623616Y-177553D01*
X623216D01*
X623616Y-177953D01*
X623216Y-178353D01*
X623616D01*
X624016Y-178753D01*
X645669D02*
X646069Y-178353D01*
X646469D01*
X646069Y-177953D01*
X646469Y-177553D01*
X646069D01*
X645669Y-177153D01*
X645269Y-177553D01*
X644869D01*
X645269Y-177953D01*
X644869Y-178353D01*
X645269D01*
X645669Y-178753D01*
X624016Y-162217D02*
X624416Y-161817D01*
X624816D01*
X624416Y-161417D01*
X624816Y-161017D01*
X624416D01*
X624016Y-160617D01*
X623616Y-161017D01*
X623216D01*
X623616Y-161417D01*
X623216Y-161817D01*
X623616D01*
X624016Y-162217D01*
X645669D02*
X646069Y-161817D01*
X646469D01*
X646069Y-161417D01*
X646469Y-161017D01*
X646069D01*
X645669Y-160617D01*
X645269Y-161017D01*
X644869D01*
X645269Y-161417D01*
X644869Y-161817D01*
X645269D01*
X645669Y-162217D01*
X674409D02*
X673609Y-160617D01*
X675210D01*
X674409Y-162217D01*
X390744Y-161277D02*
X391144Y-160477D01*
X390744Y-159677D01*
X391545Y-160077D01*
X392344Y-159677D01*
X391945Y-160477D01*
X392344Y-161277D01*
X391545Y-160877D01*
X390744Y-161277D01*
X469485D02*
X469885Y-160477D01*
X469485Y-159677D01*
X470285Y-160077D01*
X471085Y-159677D01*
X470685Y-160477D01*
X471085Y-161277D01*
X470285Y-160877D01*
X469485Y-161277D01*
X527595Y-195480D02*
X527995Y-194680D01*
X527595Y-193880D01*
X528395Y-194280D01*
X529195Y-193880D01*
X528795Y-194680D01*
X529195Y-195480D01*
X528395Y-195080D01*
X527595Y-195480D01*
Y-274220D02*
X527995Y-273420D01*
X527595Y-272620D01*
X528395Y-273020D01*
X529195Y-272620D01*
X528795Y-273420D01*
X529195Y-274220D01*
X528395Y-273820D01*
X527595Y-274220D01*
X469475Y-309398D02*
X469875Y-308597D01*
X469475Y-307798D01*
X470275Y-308197D01*
X471075Y-307798D01*
X470675Y-308597D01*
X471075Y-309398D01*
X470275Y-308998D01*
X469475Y-309398D01*
X390735D02*
X391135Y-308597D01*
X390735Y-307798D01*
X391535Y-308197D01*
X392335Y-307798D01*
X391935Y-308597D01*
X392335Y-309398D01*
X391535Y-308998D01*
X390735Y-309398D01*
X340104Y-274210D02*
X340504Y-273410D01*
X340104Y-272610D01*
X340904Y-273010D01*
X341704Y-272610D01*
X341304Y-273410D01*
X341704Y-274210D01*
X340904Y-273810D01*
X340104Y-274210D01*
Y-195470D02*
X340504Y-194670D01*
X340104Y-193870D01*
X340904Y-194270D01*
X341704Y-193870D01*
X341304Y-194670D01*
X341704Y-195470D01*
X340904Y-195070D01*
X340104Y-195470D01*
X532615Y-313164D02*
Y-313564D01*
X533415D01*
Y-313164D01*
X533815D01*
Y-312364D01*
X533415D01*
Y-311964D01*
X532615D01*
Y-312364D01*
X532215D01*
Y-313164D01*
X532615D01*
X336015Y-156164D02*
Y-156564D01*
X336815D01*
Y-156164D01*
X337215D01*
Y-155364D01*
X336815D01*
Y-154964D01*
X336015D01*
Y-155364D01*
X335615D01*
Y-156164D01*
X336015D01*
X336115Y-313164D02*
Y-313564D01*
X336915D01*
Y-313164D01*
X337315D01*
Y-312364D01*
X336915D01*
Y-311964D01*
X336115D01*
Y-312364D01*
X335715D01*
Y-313164D01*
X336115D01*
X532615Y-156164D02*
Y-156564D01*
X533415D01*
Y-156164D01*
X533815D01*
Y-155364D01*
X533415D01*
Y-154964D01*
X532615D01*
Y-155364D01*
X532215D01*
Y-156164D01*
X532615D01*
X603491Y-330839D02*
X603891D01*
X604291Y-330439D01*
X604691Y-330839D01*
X605091D01*
Y-330439D01*
X604691Y-330039D01*
X605091Y-329639D01*
Y-329239D01*
X604691D01*
X604291Y-329639D01*
X603891Y-329239D01*
X603491D01*
Y-329639D01*
X603891Y-330039D01*
X603491Y-330439D01*
Y-330839D01*
X573491D02*
X573891D01*
X574291Y-330439D01*
X574691Y-330839D01*
X575091D01*
Y-330439D01*
X574691Y-330039D01*
X575091Y-329639D01*
Y-329239D01*
X574691D01*
X574291Y-329639D01*
X573891Y-329239D01*
X573491D01*
Y-329639D01*
X573891Y-330039D01*
X573491Y-330439D01*
Y-330839D01*
X-19264Y-326781D02*
X-18464Y-325981D01*
X-17664Y-326781D01*
X-18464Y-327581D01*
X-19264Y-326781D01*
X-9264Y-317581D02*
Y-315981D01*
X-7665D01*
Y-317581D01*
X-9264D01*
X-8864Y-317181D02*
Y-316381D01*
X-8065D01*
Y-317181D01*
X-8864D01*
X735Y-326781D02*
X1535Y-325981D01*
X2335Y-326781D01*
X1535Y-327581D01*
X735Y-326781D01*
Y-306781D02*
X1535Y-305981D01*
X2335Y-306781D01*
X1535Y-307581D01*
X735Y-306781D01*
X-19264D02*
X-18464Y-305981D01*
X-17664Y-306781D01*
X-18464Y-307581D01*
X-19264Y-306781D01*
X-19265Y-273630D02*
X-18465Y-272830D01*
X-17665Y-273630D01*
X-18465Y-274430D01*
X-19265Y-273630D01*
X-9265Y-264430D02*
Y-262830D01*
X-7665D01*
Y-264430D01*
X-9265D01*
X-8865Y-264030D02*
Y-263230D01*
X-8065D01*
Y-264030D01*
X-8865D01*
X735Y-273630D02*
X1535Y-272830D01*
X2335Y-273630D01*
X1535Y-274430D01*
X735Y-273630D01*
Y-253630D02*
X1535Y-252830D01*
X2335Y-253630D01*
X1535Y-254430D01*
X735Y-253630D01*
X-19265D02*
X-18465Y-252830D01*
X-17665Y-253630D01*
X-18465Y-254430D01*
X-19265Y-253630D01*
Y-220480D02*
X-18465Y-219680D01*
X-17665Y-220480D01*
X-18465Y-221280D01*
X-19265Y-220480D01*
X-9265Y-211280D02*
Y-209680D01*
X-7665D01*
Y-211280D01*
X-9265D01*
X-8865Y-210880D02*
Y-210080D01*
X-8065D01*
Y-210880D01*
X-8865D01*
X735Y-220480D02*
X1535Y-219680D01*
X2335Y-220480D01*
X1535Y-221280D01*
X735Y-220480D01*
Y-200480D02*
X1535Y-199680D01*
X2335Y-200480D01*
X1535Y-201280D01*
X735Y-200480D01*
X-19265D02*
X-18465Y-199680D01*
X-17665Y-200480D01*
X-18465Y-201280D01*
X-19265Y-200480D01*
X-19264Y-167332D02*
X-18464Y-166532D01*
X-17664Y-167332D01*
X-18464Y-168132D01*
X-19264Y-167332D01*
X-9264Y-158132D02*
Y-156532D01*
X-7665D01*
Y-158132D01*
X-9264D01*
X-8864Y-157732D02*
Y-156932D01*
X-8065D01*
Y-157732D01*
X-8864D01*
X735Y-167332D02*
X1535Y-166532D01*
X2335Y-167332D01*
X1535Y-168132D01*
X735Y-167332D01*
Y-147332D02*
X1535Y-146532D01*
X2335Y-147332D01*
X1535Y-148132D01*
X735Y-147332D01*
X-19264D02*
X-18464Y-146532D01*
X-17664Y-147332D01*
X-18464Y-148132D01*
X-19264Y-147332D01*
X588255Y13137D02*
Y14737D01*
X589855D01*
Y13137D01*
X588255D01*
X578255D02*
Y14737D01*
X579855D01*
Y13137D01*
X578255D01*
X568255D02*
Y14737D01*
X569855D01*
Y13137D01*
X568255D01*
X558255D02*
Y14737D01*
X559855D01*
Y13137D01*
X558255D01*
X548255D02*
Y14737D01*
X549855D01*
Y13137D01*
X548255D01*
X538255D02*
Y14737D01*
X539855D01*
Y13137D01*
X538255D01*
X588255Y3137D02*
Y4737D01*
X589855D01*
Y3137D01*
X588255D01*
X578255D02*
Y4737D01*
X579855D01*
Y3137D01*
X578255D01*
X568255D02*
Y4737D01*
X569855D01*
Y3137D01*
X568255D01*
X558255D02*
Y4737D01*
X559855D01*
Y3137D01*
X558255D01*
X548255D02*
Y4737D01*
X549855D01*
Y3137D01*
X548255D01*
X538255D02*
Y4737D01*
X539855D01*
Y3137D01*
X538255D01*
X0Y-800D02*
X-800Y800D01*
X800D01*
X0Y-800D01*
Y-400D02*
X-400Y400D01*
X400D01*
X0Y-400D01*
X0Y-379195D02*
X-800Y-377595D01*
X800D01*
X0Y-379195D01*
Y-378795D02*
X-400Y-377995D01*
X400D01*
X0Y-378795D01*
X416835Y-197381D02*
X417235Y-196981D01*
X417635D01*
X417235Y-196581D01*
X417635Y-196181D01*
X417235D01*
X416835Y-195781D01*
X416435Y-196181D01*
X416035D01*
X416435Y-196581D01*
X416035Y-196981D01*
X416435D01*
X416835Y-197381D01*
Y-196981D02*
X417035Y-196781D01*
X417235D01*
X417035Y-196581D01*
X417235Y-196381D01*
X417035D01*
X416835Y-196181D01*
X416635Y-196381D01*
X416435D01*
X416635Y-196581D01*
X416435Y-196781D01*
X416635D01*
X416835Y-196981D01*
X411811Y-197650D02*
X412211Y-197250D01*
X412611D01*
X412211Y-196850D01*
X412611Y-196450D01*
X412211D01*
X411811Y-196050D01*
X411411Y-196450D01*
X411011D01*
X411411Y-196850D01*
X411011Y-197250D01*
X411411D01*
X411811Y-197650D01*
Y-197250D02*
X412011Y-197050D01*
X412211D01*
X412011Y-196850D01*
X412211Y-196650D01*
X412011D01*
X411811Y-196450D01*
X411611Y-196650D01*
X411411D01*
X411611Y-196850D01*
X411411Y-197050D01*
X411611D01*
X411811Y-197250D01*
X610617Y-228753D02*
X611017Y-227953D01*
X610617Y-227153D01*
X611417Y-227553D01*
X612217Y-227153D01*
X611817Y-227953D01*
X612217Y-228753D01*
X611417Y-228353D01*
X610617Y-228753D01*
X611017Y-228353D02*
X611217Y-227953D01*
X611017Y-227553D01*
X611417Y-227753D01*
X611817Y-227553D01*
X611617Y-227953D01*
X611817Y-228353D01*
X611417Y-228153D01*
X611017Y-228353D01*
X610617Y-224028D02*
X611017Y-223228D01*
X610617Y-222428D01*
X611417Y-222828D01*
X612217Y-222428D01*
X611817Y-223228D01*
X612217Y-224028D01*
X611417Y-223628D01*
X610617Y-224028D01*
X611017Y-223628D02*
X611217Y-223228D01*
X611017Y-222828D01*
X611417Y-223028D01*
X611817Y-222828D01*
X611617Y-223228D01*
X611817Y-223628D01*
X611417Y-223428D01*
X611017Y-223628D01*
X603924Y-228753D02*
X604324Y-227953D01*
X603924Y-227153D01*
X604724Y-227553D01*
X605524Y-227153D01*
X605124Y-227953D01*
X605524Y-228753D01*
X604724Y-228353D01*
X603924Y-228753D01*
X604324Y-228353D02*
X604524Y-227953D01*
X604324Y-227553D01*
X604724Y-227753D01*
X605124Y-227553D01*
X604924Y-227953D01*
X605124Y-228353D01*
X604724Y-228153D01*
X604324Y-228353D01*
X593307Y-128753D02*
X593707Y-128353D01*
X594107D01*
X593707Y-127953D01*
X594107Y-127553D01*
X593707D01*
X593307Y-127153D01*
X592907Y-127553D01*
X592507D01*
X592907Y-127953D01*
X592507Y-128353D01*
X592907D01*
X593307Y-128753D01*
Y-128353D02*
X593507Y-128153D01*
X593707D01*
X593507Y-127953D01*
X593707Y-127753D01*
X593507D01*
X593307Y-127553D01*
X593107Y-127753D01*
X592907D01*
X593107Y-127953D01*
X592907Y-128153D01*
X593107D01*
X593307Y-128353D01*
X570866Y-71272D02*
X571266Y-70872D01*
X571666D01*
X571266Y-70472D01*
X571666Y-70072D01*
X571266D01*
X570866Y-69672D01*
X570466Y-70072D01*
X570066D01*
X570466Y-70472D01*
X570066Y-70872D01*
X570466D01*
X570866Y-71272D01*
Y-70872D02*
X571066Y-70672D01*
X571266D01*
X571066Y-70472D01*
X571266Y-70272D01*
X571066D01*
X570866Y-70072D01*
X570666Y-70272D01*
X570466D01*
X570666Y-70472D01*
X570466Y-70672D01*
X570666D01*
X570866Y-70872D01*
Y-73241D02*
X571266Y-72841D01*
X571666D01*
X571266Y-72441D01*
X571666Y-72041D01*
X571266D01*
X570866Y-71641D01*
X570466Y-72041D01*
X570066D01*
X570466Y-72441D01*
X570066Y-72841D01*
X570466D01*
X570866Y-73241D01*
Y-72841D02*
X571066Y-72641D01*
X571266D01*
X571066Y-72441D01*
X571266Y-72241D01*
X571066D01*
X570866Y-72041D01*
X570666Y-72241D01*
X570466D01*
X570666Y-72441D01*
X570466Y-72641D01*
X570666D01*
X570866Y-72841D01*
Y-75209D02*
X571266Y-74809D01*
X571666D01*
X571266Y-74410D01*
X571666Y-74010D01*
X571266D01*
X570866Y-73610D01*
X570466Y-74010D01*
X570066D01*
X570466Y-74410D01*
X570066Y-74809D01*
X570466D01*
X570866Y-75209D01*
Y-74809D02*
X571066Y-74610D01*
X571266D01*
X571066Y-74410D01*
X571266Y-74209D01*
X571066D01*
X570866Y-74010D01*
X570666Y-74209D01*
X570466D01*
X570666Y-74410D01*
X570466Y-74610D01*
X570666D01*
X570866Y-74809D01*
X574016Y-71272D02*
X574416Y-70872D01*
X574816D01*
X574416Y-70472D01*
X574816Y-70072D01*
X574416D01*
X574016Y-69672D01*
X573616Y-70072D01*
X573216D01*
X573616Y-70472D01*
X573216Y-70872D01*
X573616D01*
X574016Y-71272D01*
Y-70872D02*
X574216Y-70672D01*
X574416D01*
X574216Y-70472D01*
X574416Y-70272D01*
X574216D01*
X574016Y-70072D01*
X573816Y-70272D01*
X573616D01*
X573816Y-70472D01*
X573616Y-70672D01*
X573816D01*
X574016Y-70872D01*
Y-73241D02*
X574416Y-72841D01*
X574816D01*
X574416Y-72441D01*
X574816Y-72041D01*
X574416D01*
X574016Y-71641D01*
X573616Y-72041D01*
X573216D01*
X573616Y-72441D01*
X573216Y-72841D01*
X573616D01*
X574016Y-73241D01*
Y-72841D02*
X574216Y-72641D01*
X574416D01*
X574216Y-72441D01*
X574416Y-72241D01*
X574216D01*
X574016Y-72041D01*
X573816Y-72241D01*
X573616D01*
X573816Y-72441D01*
X573616Y-72641D01*
X573816D01*
X574016Y-72841D01*
Y-75209D02*
X574416Y-74809D01*
X574816D01*
X574416Y-74410D01*
X574816Y-74010D01*
X574416D01*
X574016Y-73610D01*
X573616Y-74010D01*
X573216D01*
X573616Y-74410D01*
X573216Y-74809D01*
X573616D01*
X574016Y-75209D01*
Y-74809D02*
X574216Y-74610D01*
X574416D01*
X574216Y-74410D01*
X574416Y-74209D01*
X574216D01*
X574016Y-74010D01*
X573816Y-74209D01*
X573616D01*
X573816Y-74410D01*
X573616Y-74610D01*
X573816D01*
X574016Y-74809D01*
X350787Y-117729D02*
X351187Y-117329D01*
X351587D01*
X351187Y-116929D01*
X351587Y-116529D01*
X351187D01*
X350787Y-116129D01*
X350387Y-116529D01*
X349987D01*
X350387Y-116929D01*
X349987Y-117329D01*
X350387D01*
X350787Y-117729D01*
Y-117329D02*
X350987Y-117129D01*
X351187D01*
X350987Y-116929D01*
X351187Y-116729D01*
X350987D01*
X350787Y-116529D01*
X350587Y-116729D01*
X350387D01*
X350587Y-116929D01*
X350387Y-117129D01*
X350587D01*
X350787Y-117329D01*
X352756Y-117729D02*
X353156Y-117329D01*
X353556D01*
X353156Y-116929D01*
X353556Y-116529D01*
X353156D01*
X352756Y-116129D01*
X352356Y-116529D01*
X351956D01*
X352356Y-116929D01*
X351956Y-117329D01*
X352356D01*
X352756Y-117729D01*
Y-117329D02*
X352956Y-117129D01*
X353156D01*
X352956Y-116929D01*
X353156Y-116729D01*
X352956D01*
X352756Y-116529D01*
X352556Y-116729D01*
X352356D01*
X352556Y-116929D01*
X352356Y-117129D01*
X352556D01*
X352756Y-117329D01*
X354724Y-117729D02*
X355124Y-117329D01*
X355524D01*
X355124Y-116929D01*
X355524Y-116529D01*
X355124D01*
X354724Y-116129D01*
X354324Y-116529D01*
X353924D01*
X354324Y-116929D01*
X353924Y-117329D01*
X354324D01*
X354724Y-117729D01*
Y-117329D02*
X354924Y-117129D01*
X355124D01*
X354924Y-116929D01*
X355124Y-116729D01*
X354924D01*
X354724Y-116529D01*
X354524Y-116729D01*
X354324D01*
X354524Y-116929D01*
X354324Y-117129D01*
X354524D01*
X354724Y-117329D01*
X350787Y-114579D02*
X351187Y-114180D01*
X351587D01*
X351187Y-113779D01*
X351587Y-113380D01*
X351187D01*
X350787Y-112979D01*
X350387Y-113380D01*
X349987D01*
X350387Y-113779D01*
X349987Y-114180D01*
X350387D01*
X350787Y-114579D01*
Y-114180D02*
X350987Y-113979D01*
X351187D01*
X350987Y-113779D01*
X351187Y-113579D01*
X350987D01*
X350787Y-113380D01*
X350587Y-113579D01*
X350387D01*
X350587Y-113779D01*
X350387Y-113979D01*
X350587D01*
X350787Y-114180D01*
X352756Y-114579D02*
X353156Y-114180D01*
X353556D01*
X353156Y-113779D01*
X353556Y-113380D01*
X353156D01*
X352756Y-112979D01*
X352356Y-113380D01*
X351956D01*
X352356Y-113779D01*
X351956Y-114180D01*
X352356D01*
X352756Y-114579D01*
Y-114180D02*
X352956Y-113979D01*
X353156D01*
X352956Y-113779D01*
X353156Y-113579D01*
X352956D01*
X352756Y-113380D01*
X352556Y-113579D01*
X352356D01*
X352556Y-113779D01*
X352356Y-113979D01*
X352556D01*
X352756Y-114180D01*
X354724Y-114579D02*
X355124Y-114180D01*
X355524D01*
X355124Y-113779D01*
X355524Y-113380D01*
X355124D01*
X354724Y-112979D01*
X354324Y-113380D01*
X353924D01*
X354324Y-113779D01*
X353924Y-114180D01*
X354324D01*
X354724Y-114579D01*
Y-114180D02*
X354924Y-113979D01*
X355124D01*
X354924Y-113779D01*
X355124Y-113579D01*
X354924D01*
X354724Y-113380D01*
X354524Y-113579D01*
X354324D01*
X354524Y-113779D01*
X354324Y-113979D01*
X354524D01*
X354724Y-114180D01*
X379134Y-138595D02*
X379534Y-138195D01*
X379934D01*
X379534Y-137795D01*
X379934Y-137395D01*
X379534D01*
X379134Y-136995D01*
X378734Y-137395D01*
X378334D01*
X378734Y-137795D01*
X378334Y-138195D01*
X378734D01*
X379134Y-138595D01*
Y-138195D02*
X379334Y-137995D01*
X379534D01*
X379334Y-137795D01*
X379534Y-137595D01*
X379334D01*
X379134Y-137395D01*
X378934Y-137595D01*
X378734D01*
X378934Y-137795D01*
X378734Y-137995D01*
X378934D01*
X379134Y-138195D01*
X375984Y-120879D02*
X376384Y-120479D01*
X376784D01*
X376384Y-120079D01*
X376784Y-119679D01*
X376384D01*
X375984Y-119279D01*
X375584Y-119679D01*
X375184D01*
X375584Y-120079D01*
X375184Y-120479D01*
X375584D01*
X375984Y-120879D01*
Y-120479D02*
X376184Y-120279D01*
X376384D01*
X376184Y-120079D01*
X376384Y-119879D01*
X376184D01*
X375984Y-119679D01*
X375784Y-119879D01*
X375584D01*
X375784Y-120079D01*
X375584Y-120279D01*
X375784D01*
X375984Y-120479D01*
X375532Y-124410D02*
X375932Y-124010D01*
X376332D01*
X375932Y-123610D01*
X376332Y-123210D01*
X375932D01*
X375532Y-122810D01*
X375132Y-123210D01*
X374732D01*
X375132Y-123610D01*
X374732Y-124010D01*
X375132D01*
X375532Y-124410D01*
Y-124010D02*
X375732Y-123810D01*
X375932D01*
X375732Y-123610D01*
X375932Y-123410D01*
X375732D01*
X375532Y-123210D01*
X375332Y-123410D01*
X375132D01*
X375332Y-123610D01*
X375132Y-123810D01*
X375332D01*
X375532Y-124010D01*
X314658Y-245575D02*
X315058Y-245175D01*
X315458D01*
X315058Y-244775D01*
X315458Y-244375D01*
X315058D01*
X314658Y-243975D01*
X314258Y-244375D01*
X313858D01*
X314258Y-244775D01*
X313858Y-245175D01*
X314258D01*
X314658Y-245575D01*
Y-245175D02*
X314858Y-244975D01*
X315058D01*
X314858Y-244775D01*
X315058Y-244575D01*
X314858D01*
X314658Y-244375D01*
X314458Y-244575D01*
X314258D01*
X314458Y-244775D01*
X314258Y-244975D01*
X314458D01*
X314658Y-245175D01*
X315097Y-235881D02*
X315497Y-235481D01*
X315897D01*
X315497Y-235081D01*
X315897Y-234681D01*
X315497D01*
X315097Y-234281D01*
X314697Y-234681D01*
X314297D01*
X314697Y-235081D01*
X314297Y-235481D01*
X314697D01*
X315097Y-235881D01*
Y-235481D02*
X315297Y-235281D01*
X315497D01*
X315297Y-235081D01*
X315497Y-234881D01*
X315297D01*
X315097Y-234681D01*
X314897Y-234881D01*
X314697D01*
X314897Y-235081D01*
X314697Y-235281D01*
X314897D01*
X315097Y-235481D01*
X315226Y-231434D02*
X315626Y-231034D01*
X316026D01*
X315626Y-230634D01*
X316026Y-230234D01*
X315626D01*
X315226Y-229834D01*
X314826Y-230234D01*
X314426D01*
X314826Y-230634D01*
X314426Y-231034D01*
X314826D01*
X315226Y-231434D01*
Y-231034D02*
X315426Y-230834D01*
X315626D01*
X315426Y-230634D01*
X315626Y-230434D01*
X315426D01*
X315226Y-230234D01*
X315026Y-230434D01*
X314826D01*
X315026Y-230634D01*
X314826Y-230834D01*
X315026D01*
X315226Y-231034D01*
X314864Y-228797D02*
X315265Y-228397D01*
X315665D01*
X315265Y-227997D01*
X315665Y-227597D01*
X315265D01*
X314864Y-227197D01*
X314464Y-227597D01*
X314065D01*
X314464Y-227997D01*
X314065Y-228397D01*
X314464D01*
X314864Y-228797D01*
Y-228397D02*
X315065Y-228197D01*
X315265D01*
X315065Y-227997D01*
X315265Y-227797D01*
X315065D01*
X314864Y-227597D01*
X314665Y-227797D01*
X314464D01*
X314665Y-227997D01*
X314464Y-228197D01*
X314665D01*
X314864Y-228397D01*
X314503Y-225980D02*
X314903Y-225580D01*
X315303D01*
X314903Y-225180D01*
X315303Y-224780D01*
X314903D01*
X314503Y-224380D01*
X314103Y-224780D01*
X313703D01*
X314103Y-225180D01*
X313703Y-225580D01*
X314103D01*
X314503Y-225980D01*
Y-225580D02*
X314703Y-225380D01*
X314903D01*
X314703Y-225180D01*
X314903Y-224980D01*
X314703D01*
X314503Y-224780D01*
X314303Y-224980D01*
X314103D01*
X314303Y-225180D01*
X314103Y-225380D01*
X314303D01*
X314503Y-225580D01*
X288583Y-226391D02*
X288983Y-225991D01*
X289383D01*
X288983Y-225590D01*
X289383Y-225190D01*
X288983D01*
X288583Y-224791D01*
X288183Y-225190D01*
X287783D01*
X288183Y-225590D01*
X287783Y-225991D01*
X288183D01*
X288583Y-226391D01*
Y-225991D02*
X288783Y-225791D01*
X288983D01*
X288783Y-225590D01*
X288983Y-225391D01*
X288783D01*
X288583Y-225190D01*
X288383Y-225391D01*
X288183D01*
X288383Y-225590D01*
X288183Y-225791D01*
X288383D01*
X288583Y-225991D01*
X288189Y-229540D02*
X288589Y-229140D01*
X288989D01*
X288589Y-228740D01*
X288989Y-228340D01*
X288589D01*
X288189Y-227940D01*
X287789Y-228340D01*
X287389D01*
X287789Y-228740D01*
X287389Y-229140D01*
X287789D01*
X288189Y-229540D01*
Y-229140D02*
X288389Y-228940D01*
X288589D01*
X288389Y-228740D01*
X288589Y-228540D01*
X288389D01*
X288189Y-228340D01*
X287989Y-228540D01*
X287789D01*
X287989Y-228740D01*
X287789Y-228940D01*
X287989D01*
X288189Y-229140D01*
Y-231902D02*
X288589Y-231502D01*
X288989D01*
X288589Y-231102D01*
X288989Y-230702D01*
X288589D01*
X288189Y-230302D01*
X287789Y-230702D01*
X287389D01*
X287789Y-231102D01*
X287389Y-231502D01*
X287789D01*
X288189Y-231902D01*
Y-231502D02*
X288389Y-231302D01*
X288589D01*
X288389Y-231102D01*
X288589Y-230902D01*
X288389D01*
X288189Y-230702D01*
X287989Y-230902D01*
X287789D01*
X287989Y-231102D01*
X287789Y-231302D01*
X287989D01*
X288189Y-231502D01*
X288057Y-234278D02*
X288457Y-233878D01*
X288857D01*
X288457Y-233478D01*
X288857Y-233078D01*
X288457D01*
X288057Y-232678D01*
X287657Y-233078D01*
X287257D01*
X287657Y-233478D01*
X287257Y-233878D01*
X287657D01*
X288057Y-234278D01*
Y-233878D02*
X288257Y-233678D01*
X288457D01*
X288257Y-233478D01*
X288457Y-233278D01*
X288257D01*
X288057Y-233078D01*
X287857Y-233278D01*
X287657D01*
X287857Y-233478D01*
X287657Y-233678D01*
X287857D01*
X288057Y-233878D01*
X288057Y-245895D02*
X288457Y-245495D01*
X288857D01*
X288457Y-245095D01*
X288857Y-244695D01*
X288457D01*
X288057Y-244295D01*
X287657Y-244695D01*
X287257D01*
X287657Y-245095D01*
X287257Y-245495D01*
X287657D01*
X288057Y-245895D01*
Y-245495D02*
X288257Y-245295D01*
X288457D01*
X288257Y-245095D01*
X288457Y-244895D01*
X288257D01*
X288057Y-244695D01*
X287857Y-244895D01*
X287657D01*
X287857Y-245095D01*
X287657Y-245295D01*
X287857D01*
X288057Y-245495D01*
X288189Y-248438D02*
X288589Y-248038D01*
X288989D01*
X288589Y-247638D01*
X288989Y-247238D01*
X288589D01*
X288189Y-246838D01*
X287789Y-247238D01*
X287389D01*
X287789Y-247638D01*
X287389Y-248038D01*
X287789D01*
X288189Y-248438D01*
Y-248038D02*
X288389Y-247838D01*
X288589D01*
X288389Y-247638D01*
X288589Y-247438D01*
X288389D01*
X288189Y-247238D01*
X287989Y-247438D01*
X287789D01*
X287989Y-247638D01*
X287789Y-247838D01*
X287989D01*
X288189Y-248038D01*
X287941Y-242619D02*
X288341Y-242219D01*
X288741D01*
X288341Y-241819D01*
X288741Y-241419D01*
X288341D01*
X287941Y-241019D01*
X287541Y-241419D01*
X287141D01*
X287541Y-241819D01*
X287141Y-242219D01*
X287541D01*
X287941Y-242619D01*
Y-242219D02*
X288141Y-242019D01*
X288341D01*
X288141Y-241819D01*
X288341Y-241619D01*
X288141D01*
X287941Y-241419D01*
X287741Y-241619D01*
X287541D01*
X287741Y-241819D01*
X287541Y-242019D01*
X287741D01*
X287941Y-242219D01*
X288189Y-236627D02*
X288589Y-236227D01*
X288989D01*
X288589Y-235827D01*
X288989Y-235427D01*
X288589D01*
X288189Y-235027D01*
X287789Y-235427D01*
X287389D01*
X287789Y-235827D01*
X287389Y-236227D01*
X287789D01*
X288189Y-236627D01*
Y-236227D02*
X288389Y-236027D01*
X288589D01*
X288389Y-235827D01*
X288589Y-235627D01*
X288389D01*
X288189Y-235427D01*
X287989Y-235627D01*
X287789D01*
X287989Y-235827D01*
X287789Y-236027D01*
X287989D01*
X288189Y-236227D01*
X588976Y-303556D02*
X589376Y-303156D01*
X589776D01*
X589376Y-302756D01*
X589776Y-302356D01*
X589376D01*
X588976Y-301956D01*
X588576Y-302356D01*
X588176D01*
X588576Y-302756D01*
X588176Y-303156D01*
X588576D01*
X588976Y-303556D01*
Y-303156D02*
X589176Y-302956D01*
X589376D01*
X589176Y-302756D01*
X589376Y-302556D01*
X589176D01*
X588976Y-302356D01*
X588776Y-302556D01*
X588576D01*
X588776Y-302756D01*
X588576Y-302956D01*
X588776D01*
X588976Y-303156D01*
X579528Y-303950D02*
X579928Y-303550D01*
X580328D01*
X579928Y-303150D01*
X580328Y-302750D01*
X579928D01*
X579528Y-302350D01*
X579128Y-302750D01*
X578728D01*
X579128Y-303150D01*
X578728Y-303550D01*
X579128D01*
X579528Y-303950D01*
Y-303550D02*
X579728Y-303350D01*
X579928D01*
X579728Y-303150D01*
X579928Y-302950D01*
X579728D01*
X579528Y-302750D01*
X579328Y-302950D01*
X579128D01*
X579328Y-303150D01*
X579128Y-303350D01*
X579328D01*
X579528Y-303550D01*
X615748Y-306312D02*
X616148Y-305912D01*
X616548D01*
X616148Y-305512D01*
X616548Y-305112D01*
X616148D01*
X615748Y-304712D01*
X615348Y-305112D01*
X614948D01*
X615348Y-305512D01*
X614948Y-305912D01*
X615348D01*
X615748Y-306312D01*
Y-305912D02*
X615948Y-305712D01*
X616148D01*
X615948Y-305512D01*
X616148Y-305312D01*
X615948D01*
X615748Y-305112D01*
X615548Y-305312D01*
X615348D01*
X615548Y-305512D01*
X615348Y-305712D01*
X615548D01*
X615748Y-305912D01*
X562598Y-307493D02*
X562998Y-307093D01*
X563398D01*
X562998Y-306693D01*
X563398Y-306293D01*
X562998D01*
X562598Y-305893D01*
X562198Y-306293D01*
X561798D01*
X562198Y-306693D01*
X561798Y-307093D01*
X562198D01*
X562598Y-307493D01*
Y-307093D02*
X562798Y-306893D01*
X562998D01*
X562798Y-306693D01*
X562998Y-306493D01*
X562798D01*
X562598Y-306293D01*
X562398Y-306493D01*
X562198D01*
X562398Y-306693D01*
X562198Y-306893D01*
X562398D01*
X562598Y-307093D01*
X330709Y-121273D02*
X331109Y-120872D01*
X331509D01*
X331109Y-120473D01*
X331509Y-120072D01*
X331109D01*
X330709Y-119673D01*
X330309Y-120072D01*
X329909D01*
X330309Y-120473D01*
X329909Y-120872D01*
X330309D01*
X330709Y-121273D01*
Y-120872D02*
X330909Y-120673D01*
X331109D01*
X330909Y-120473D01*
X331109Y-120273D01*
X330909D01*
X330709Y-120072D01*
X330509Y-120273D01*
X330309D01*
X330509Y-120473D01*
X330309Y-120673D01*
X330509D01*
X330709Y-120872D01*
Y-124225D02*
X331109Y-123825D01*
X331509D01*
X331109Y-123425D01*
X331509Y-123025D01*
X331109D01*
X330709Y-122625D01*
X330309Y-123025D01*
X329909D01*
X330309Y-123425D01*
X329909Y-123825D01*
X330309D01*
X330709Y-124225D01*
Y-123825D02*
X330909Y-123625D01*
X331109D01*
X330909Y-123425D01*
X331109Y-123225D01*
X330909D01*
X330709Y-123025D01*
X330509Y-123225D01*
X330309D01*
X330509Y-123425D01*
X330309Y-123625D01*
X330509D01*
X330709Y-123825D01*
X121063Y-264432D02*
X121463Y-264032D01*
X121863D01*
X121463Y-263632D01*
X121863Y-263231D01*
X121463D01*
X121063Y-262831D01*
X120663Y-263231D01*
X120263D01*
X120663Y-263632D01*
X120263Y-264032D01*
X120663D01*
X121063Y-264432D01*
Y-264032D02*
X121263Y-263831D01*
X121463D01*
X121263Y-263632D01*
X121463Y-263432D01*
X121263D01*
X121063Y-263231D01*
X120863Y-263432D01*
X120663D01*
X120863Y-263632D01*
X120663Y-263831D01*
X120863D01*
X121063Y-264032D01*
X347811Y-90291D02*
Y-90691D01*
X348611D01*
Y-90291D01*
X349011D01*
Y-89491D01*
X348611D01*
Y-89091D01*
X347811D01*
Y-89491D01*
X347411D01*
Y-90291D01*
X347811D01*
X348011Y-90091D02*
Y-90291D01*
X348411D01*
Y-90091D01*
X348611D01*
Y-89691D01*
X348411D01*
Y-89491D01*
X348011D01*
Y-89691D01*
X347811D01*
Y-90091D01*
X348011D01*
X357398Y-90363D02*
Y-90763D01*
X358198D01*
Y-90363D01*
X358598D01*
Y-89563D01*
X358198D01*
Y-89163D01*
X357398D01*
Y-89563D01*
X356998D01*
Y-90363D01*
X357398D01*
X357598Y-90163D02*
Y-90363D01*
X357998D01*
Y-90163D01*
X358198D01*
Y-89763D01*
X357998D01*
Y-89563D01*
X357598D01*
Y-89763D01*
X357398D01*
Y-90163D01*
X357598D01*
X375590Y-127965D02*
X375991Y-127565D01*
X376391D01*
X375991Y-127165D01*
X376391Y-126765D01*
X375991D01*
X375590Y-126365D01*
X375190Y-126765D01*
X374791D01*
X375190Y-127165D01*
X374791Y-127565D01*
X375190D01*
X375590Y-127965D01*
Y-127565D02*
X375791Y-127365D01*
X375991D01*
X375791Y-127165D01*
X375991Y-126965D01*
X375791D01*
X375590Y-126765D01*
X375391Y-126965D01*
X375190D01*
X375391Y-127165D01*
X375190Y-127365D01*
X375391D01*
X375590Y-127565D01*
X106299Y-264432D02*
X106699Y-264032D01*
X107099D01*
X106699Y-263632D01*
X107099Y-263231D01*
X106699D01*
X106299Y-262831D01*
X105899Y-263231D01*
X105499D01*
X105899Y-263632D01*
X105499Y-264032D01*
X105899D01*
X106299Y-264432D01*
Y-264032D02*
X106499Y-263831D01*
X106699D01*
X106499Y-263632D01*
X106699Y-263432D01*
X106499D01*
X106299Y-263231D01*
X106099Y-263432D01*
X105899D01*
X106099Y-263632D01*
X105899Y-263831D01*
X106099D01*
X106299Y-264032D01*
X330709Y-127178D02*
X331109Y-126778D01*
X331509D01*
X331109Y-126378D01*
X331509Y-125978D01*
X331109D01*
X330709Y-125578D01*
X330309Y-125978D01*
X329909D01*
X330309Y-126378D01*
X329909Y-126778D01*
X330309D01*
X330709Y-127178D01*
Y-126778D02*
X330909Y-126578D01*
X331109D01*
X330909Y-126378D01*
X331109Y-126178D01*
X330909D01*
X330709Y-125978D01*
X330509Y-126178D01*
X330309D01*
X330509Y-126378D01*
X330309Y-126578D01*
X330509D01*
X330709Y-126778D01*
X564096Y-237497D02*
X564496D01*
X564896Y-237097D01*
X565296Y-237497D01*
X565696D01*
Y-237097D01*
X565296Y-236697D01*
X565696Y-236297D01*
Y-235897D01*
X565296D01*
X564896Y-236297D01*
X564496Y-235897D01*
X564096D01*
Y-236297D01*
X564496Y-236697D01*
X564096Y-237097D01*
Y-237497D01*
X564496Y-237097D02*
X564696D01*
X564896Y-236897D01*
X565096Y-237097D01*
X565296D01*
Y-236897D01*
X565096Y-236697D01*
X565296Y-236497D01*
Y-236297D01*
X565096D01*
X564896Y-236497D01*
X564696Y-236297D01*
X564496D01*
Y-236497D01*
X564696Y-236697D01*
X564496Y-236897D01*
Y-237097D01*
X600000Y-146863D02*
X600400Y-146463D01*
X600800D01*
X600400Y-146063D01*
X600800Y-145663D01*
X600400D01*
X600000Y-145263D01*
X599600Y-145663D01*
X599200D01*
X599600Y-146063D01*
X599200Y-146463D01*
X599600D01*
X600000Y-146863D01*
Y-146463D02*
X600200Y-146263D01*
X600400D01*
X600200Y-146063D01*
X600400Y-145863D01*
X600200D01*
X600000Y-145663D01*
X599800Y-145863D01*
X599600D01*
X599800Y-146063D01*
X599600Y-146263D01*
X599800D01*
X600000Y-146463D01*
X598032Y-146863D02*
X598431Y-146463D01*
X598832D01*
X598431Y-146063D01*
X598832Y-145663D01*
X598431D01*
X598032Y-145263D01*
X597632Y-145663D01*
X597231D01*
X597632Y-146063D01*
X597231Y-146463D01*
X597632D01*
X598032Y-146863D01*
Y-146463D02*
X598232Y-146263D01*
X598431D01*
X598232Y-146063D01*
X598431Y-145863D01*
X598232D01*
X598032Y-145663D01*
X597831Y-145863D01*
X597632D01*
X597831Y-146063D01*
X597632Y-146263D01*
X597831D01*
X598032Y-146463D01*
X596063Y-146863D02*
X596463Y-146463D01*
X596863D01*
X596463Y-146063D01*
X596863Y-145663D01*
X596463D01*
X596063Y-145263D01*
X595663Y-145663D01*
X595263D01*
X595663Y-146063D01*
X595263Y-146463D01*
X595663D01*
X596063Y-146863D01*
Y-146463D02*
X596263Y-146263D01*
X596463D01*
X596263Y-146063D01*
X596463Y-145863D01*
X596263D01*
X596063Y-145663D01*
X595863Y-145863D01*
X595663D01*
X595863Y-146063D01*
X595663Y-146263D01*
X595863D01*
X596063Y-146463D01*
X587008Y-146863D02*
X587408Y-146463D01*
X587808D01*
X587408Y-146063D01*
X587808Y-145663D01*
X587408D01*
X587008Y-145263D01*
X586608Y-145663D01*
X586208D01*
X586608Y-146063D01*
X586208Y-146463D01*
X586608D01*
X587008Y-146863D01*
Y-146463D02*
X587208Y-146263D01*
X587408D01*
X587208Y-146063D01*
X587408Y-145863D01*
X587208D01*
X587008Y-145663D01*
X586808Y-145863D01*
X586608D01*
X586808Y-146063D01*
X586608Y-146263D01*
X586808D01*
X587008Y-146463D01*
X585039Y-146863D02*
X585439Y-146463D01*
X585839D01*
X585439Y-146063D01*
X585839Y-145663D01*
X585439D01*
X585039Y-145263D01*
X584639Y-145663D01*
X584239D01*
X584639Y-146063D01*
X584239Y-146463D01*
X584639D01*
X585039Y-146863D01*
Y-146463D02*
X585239Y-146263D01*
X585439D01*
X585239Y-146063D01*
X585439Y-145863D01*
X585239D01*
X585039Y-145663D01*
X584839Y-145863D01*
X584639D01*
X584839Y-146063D01*
X584639Y-146263D01*
X584839D01*
X585039Y-146463D01*
X583071Y-146863D02*
X583471Y-146463D01*
X583871D01*
X583471Y-146063D01*
X583871Y-145663D01*
X583471D01*
X583071Y-145263D01*
X582671Y-145663D01*
X582271D01*
X582671Y-146063D01*
X582271Y-146463D01*
X582671D01*
X583071Y-146863D01*
Y-146463D02*
X583271Y-146263D01*
X583471D01*
X583271Y-146063D01*
X583471Y-145863D01*
X583271D01*
X583071Y-145663D01*
X582871Y-145863D01*
X582671D01*
X582871Y-146063D01*
X582671Y-146263D01*
X582871D01*
X583071Y-146463D01*
X575984Y-146469D02*
X576384Y-146069D01*
X576784D01*
X576384Y-145669D01*
X576784Y-145269D01*
X576384D01*
X575984Y-144869D01*
X575584Y-145269D01*
X575184D01*
X575584Y-145669D01*
X575184Y-146069D01*
X575584D01*
X575984Y-146469D01*
Y-146069D02*
X576184Y-145869D01*
X576384D01*
X576184Y-145669D01*
X576384Y-145469D01*
X576184D01*
X575984Y-145269D01*
X575784Y-145469D01*
X575584D01*
X575784Y-145669D01*
X575584Y-145869D01*
X575784D01*
X575984Y-146069D01*
X574016Y-146469D02*
X574416Y-146069D01*
X574816D01*
X574416Y-145669D01*
X574816Y-145269D01*
X574416D01*
X574016Y-144869D01*
X573616Y-145269D01*
X573216D01*
X573616Y-145669D01*
X573216Y-146069D01*
X573616D01*
X574016Y-146469D01*
Y-146069D02*
X574216Y-145869D01*
X574416D01*
X574216Y-145669D01*
X574416Y-145469D01*
X574216D01*
X574016Y-145269D01*
X573816Y-145469D01*
X573616D01*
X573816Y-145669D01*
X573616Y-145869D01*
X573816D01*
X574016Y-146069D01*
X572047Y-146469D02*
X572447Y-146069D01*
X572847D01*
X572447Y-145669D01*
X572847Y-145269D01*
X572447D01*
X572047Y-144869D01*
X571647Y-145269D01*
X571247D01*
X571647Y-145669D01*
X571247Y-146069D01*
X571647D01*
X572047Y-146469D01*
Y-146069D02*
X572247Y-145869D01*
X572447D01*
X572247Y-145669D01*
X572447Y-145469D01*
X572247D01*
X572047Y-145269D01*
X571847Y-145469D01*
X571647D01*
X571847Y-145669D01*
X571647Y-145869D01*
X571847D01*
X572047Y-146069D01*
X593307Y-131902D02*
X593707Y-131502D01*
X594107D01*
X593707Y-131102D01*
X594107Y-130702D01*
X593707D01*
X593307Y-130302D01*
X592907Y-130702D01*
X592507D01*
X592907Y-131102D01*
X592507Y-131502D01*
X592907D01*
X593307Y-131902D01*
Y-131502D02*
X593507Y-131302D01*
X593707D01*
X593507Y-131102D01*
X593707Y-130902D01*
X593507D01*
X593307Y-130702D01*
X593107Y-130902D01*
X592907D01*
X593107Y-131102D01*
X592907Y-131302D01*
X593107D01*
X593307Y-131502D01*
X595276Y-131902D02*
X595676Y-131502D01*
X596076D01*
X595676Y-131102D01*
X596076Y-130702D01*
X595676D01*
X595276Y-130302D01*
X594876Y-130702D01*
X594476D01*
X594876Y-131102D01*
X594476Y-131502D01*
X594876D01*
X595276Y-131902D01*
Y-131502D02*
X595476Y-131302D01*
X595676D01*
X595476Y-131102D01*
X595676Y-130902D01*
X595476D01*
X595276Y-130702D01*
X595076Y-130902D01*
X594876D01*
X595076Y-131102D01*
X594876Y-131302D01*
X595076D01*
X595276Y-131502D01*
X597244Y-131902D02*
X597644Y-131502D01*
X598044D01*
X597644Y-131102D01*
X598044Y-130702D01*
X597644D01*
X597244Y-130302D01*
X596844Y-130702D01*
X596444D01*
X596844Y-131102D01*
X596444Y-131502D01*
X596844D01*
X597244Y-131902D01*
Y-131502D02*
X597444Y-131302D01*
X597644D01*
X597444Y-131102D01*
X597644Y-130902D01*
X597444D01*
X597244Y-130702D01*
X597044Y-130902D01*
X596844D01*
X597044Y-131102D01*
X596844Y-131302D01*
X597044D01*
X597244Y-131502D01*
X595276Y-128753D02*
X595676Y-128353D01*
X596076D01*
X595676Y-127953D01*
X596076Y-127553D01*
X595676D01*
X595276Y-127153D01*
X594876Y-127553D01*
X594476D01*
X594876Y-127953D01*
X594476Y-128353D01*
X594876D01*
X595276Y-128753D01*
Y-128353D02*
X595476Y-128153D01*
X595676D01*
X595476Y-127953D01*
X595676Y-127753D01*
X595476D01*
X595276Y-127553D01*
X595076Y-127753D01*
X594876D01*
X595076Y-127953D01*
X594876Y-128153D01*
X595076D01*
X595276Y-128353D01*
X597244Y-128753D02*
X597644Y-128353D01*
X598044D01*
X597644Y-127953D01*
X598044Y-127553D01*
X597644D01*
X597244Y-127153D01*
X596844Y-127553D01*
X596444D01*
X596844Y-127953D01*
X596444Y-128353D01*
X596844D01*
X597244Y-128753D01*
Y-128353D02*
X597444Y-128153D01*
X597644D01*
X597444Y-127953D01*
X597644Y-127753D01*
X597444D01*
X597244Y-127553D01*
X597044Y-127753D01*
X596844D01*
X597044Y-127953D01*
X596844Y-128153D01*
X597044D01*
X597244Y-128353D01*
X598019Y-229147D02*
X598419Y-228346D01*
X598019Y-227547D01*
X598819Y-227946D01*
X599619Y-227547D01*
X599219Y-228346D01*
X599619Y-229147D01*
X598819Y-228747D01*
X598019Y-229147D01*
X598419Y-228747D02*
X598619Y-228346D01*
X598419Y-227946D01*
X598819Y-228147D01*
X599219Y-227946D01*
X599019Y-228346D01*
X599219Y-228747D01*
X598819Y-228547D01*
X598419Y-228747D01*
X603924Y-223635D02*
X604324Y-222835D01*
X603924Y-222035D01*
X604724Y-222435D01*
X605524Y-222035D01*
X605124Y-222835D01*
X605524Y-223635D01*
X604724Y-223235D01*
X603924Y-223635D01*
X604324Y-223235D02*
X604524Y-222835D01*
X604324Y-222435D01*
X604724Y-222635D01*
X605124Y-222435D01*
X604924Y-222835D01*
X605124Y-223235D01*
X604724Y-223035D01*
X604324Y-223235D01*
X650787Y-230721D02*
X651187Y-230321D01*
X651587D01*
X651187Y-229921D01*
X651587Y-229521D01*
X651187D01*
X650787Y-229121D01*
X650387Y-229521D01*
X649987D01*
X650387Y-229921D01*
X649987Y-230321D01*
X650387D01*
X650787Y-230721D01*
Y-230321D02*
X650987Y-230121D01*
X651187D01*
X650987Y-229921D01*
X651187Y-229721D01*
X650987D01*
X650787Y-229521D01*
X650587Y-229721D01*
X650387D01*
X650587Y-229921D01*
X650387Y-230121D01*
X650587D01*
X650787Y-230321D01*
X645669Y-231115D02*
X646069Y-230715D01*
X646469D01*
X646069Y-230315D01*
X646469Y-229915D01*
X646069D01*
X645669Y-229515D01*
X645269Y-229915D01*
X644869D01*
X645269Y-230315D01*
X644869Y-230715D01*
X645269D01*
X645669Y-231115D01*
Y-230715D02*
X645869Y-230515D01*
X646069D01*
X645869Y-230315D01*
X646069Y-230115D01*
X645869D01*
X645669Y-229915D01*
X645469Y-230115D01*
X645269D01*
X645469Y-230315D01*
X645269Y-230515D01*
X645469D01*
X645669Y-230715D01*
X641732Y-231115D02*
X642132Y-230715D01*
X642532D01*
X642132Y-230315D01*
X642532Y-229915D01*
X642132D01*
X641732Y-229515D01*
X641332Y-229915D01*
X640932D01*
X641332Y-230315D01*
X640932Y-230715D01*
X641332D01*
X641732Y-231115D01*
Y-230715D02*
X641932Y-230515D01*
X642132D01*
X641932Y-230315D01*
X642132Y-230115D01*
X641932D01*
X641732Y-229915D01*
X641532Y-230115D01*
X641332D01*
X641532Y-230315D01*
X641332Y-230515D01*
X641532D01*
X641732Y-230715D01*
X638189Y-231115D02*
X638589Y-230715D01*
X638989D01*
X638589Y-230315D01*
X638989Y-229915D01*
X638589D01*
X638189Y-229515D01*
X637789Y-229915D01*
X637389D01*
X637789Y-230315D01*
X637389Y-230715D01*
X637789D01*
X638189Y-231115D01*
Y-230715D02*
X638389Y-230515D01*
X638589D01*
X638389Y-230315D01*
X638589Y-230115D01*
X638389D01*
X638189Y-229915D01*
X637989Y-230115D01*
X637789D01*
X637989Y-230315D01*
X637789Y-230515D01*
X637989D01*
X638189Y-230715D01*
X640945Y-251194D02*
X641345Y-250794D01*
X641745D01*
X641345Y-250394D01*
X641745Y-249994D01*
X641345D01*
X640945Y-249594D01*
X640545Y-249994D01*
X640145D01*
X640545Y-250394D01*
X640145Y-250794D01*
X640545D01*
X640945Y-251194D01*
Y-250794D02*
X641145Y-250594D01*
X641345D01*
X641145Y-250394D01*
X641345Y-250194D01*
X641145D01*
X640945Y-249994D01*
X640745Y-250194D01*
X640545D01*
X640745Y-250394D01*
X640545Y-250594D01*
X640745D01*
X640945Y-250794D01*
Y-249225D02*
X641345Y-248825D01*
X641745D01*
X641345Y-248425D01*
X641745Y-248025D01*
X641345D01*
X640945Y-247625D01*
X640545Y-248025D01*
X640145D01*
X640545Y-248425D01*
X640145Y-248825D01*
X640545D01*
X640945Y-249225D01*
Y-248825D02*
X641145Y-248625D01*
X641345D01*
X641145Y-248425D01*
X641345Y-248225D01*
X641145D01*
X640945Y-248025D01*
X640745Y-248225D01*
X640545D01*
X640745Y-248425D01*
X640545Y-248625D01*
X640745D01*
X640945Y-248825D01*
Y-247257D02*
X641345Y-246857D01*
X641745D01*
X641345Y-246457D01*
X641745Y-246057D01*
X641345D01*
X640945Y-245657D01*
X640545Y-246057D01*
X640145D01*
X640545Y-246457D01*
X640145Y-246857D01*
X640545D01*
X640945Y-247257D01*
Y-246857D02*
X641145Y-246657D01*
X641345D01*
X641145Y-246457D01*
X641345Y-246257D01*
X641145D01*
X640945Y-246057D01*
X640745Y-246257D01*
X640545D01*
X640745Y-246457D01*
X640545Y-246657D01*
X640745D01*
X640945Y-246857D01*
X637795Y-251194D02*
X638195Y-250794D01*
X638595D01*
X638195Y-250394D01*
X638595Y-249994D01*
X638195D01*
X637795Y-249594D01*
X637395Y-249994D01*
X636995D01*
X637395Y-250394D01*
X636995Y-250794D01*
X637395D01*
X637795Y-251194D01*
Y-250794D02*
X637995Y-250594D01*
X638195D01*
X637995Y-250394D01*
X638195Y-250194D01*
X637995D01*
X637795Y-249994D01*
X637595Y-250194D01*
X637395D01*
X637595Y-250394D01*
X637395Y-250594D01*
X637595D01*
X637795Y-250794D01*
Y-249225D02*
X638195Y-248825D01*
X638595D01*
X638195Y-248425D01*
X638595Y-248025D01*
X638195D01*
X637795Y-247625D01*
X637395Y-248025D01*
X636995D01*
X637395Y-248425D01*
X636995Y-248825D01*
X637395D01*
X637795Y-249225D01*
Y-248825D02*
X637995Y-248625D01*
X638195D01*
X637995Y-248425D01*
X638195Y-248225D01*
X637995D01*
X637795Y-248025D01*
X637595Y-248225D01*
X637395D01*
X637595Y-248425D01*
X637395Y-248625D01*
X637595D01*
X637795Y-248825D01*
Y-247257D02*
X638195Y-246857D01*
X638595D01*
X638195Y-246457D01*
X638595Y-246057D01*
X638195D01*
X637795Y-245657D01*
X637395Y-246057D01*
X636995D01*
X637395Y-246457D01*
X636995Y-246857D01*
X637395D01*
X637795Y-247257D01*
Y-246857D02*
X637995Y-246657D01*
X638195D01*
X637995Y-246457D01*
X638195Y-246257D01*
X637995D01*
X637795Y-246057D01*
X637595Y-246257D01*
X637395D01*
X637595Y-246457D01*
X637395Y-246657D01*
X637595D01*
X637795Y-246857D01*
X654724Y-212217D02*
X655124Y-211817D01*
X655524D01*
X655124Y-211417D01*
X655524Y-211017D01*
X655124D01*
X654724Y-210617D01*
X654324Y-211017D01*
X653924D01*
X654324Y-211417D01*
X653924Y-211817D01*
X654324D01*
X654724Y-212217D01*
Y-211817D02*
X654924Y-211617D01*
X655124D01*
X654924Y-211417D01*
X655124Y-211217D01*
X654924D01*
X654724Y-211017D01*
X654524Y-211217D01*
X654324D01*
X654524Y-211417D01*
X654324Y-211617D01*
X654524D01*
X654724Y-211817D01*
X656693Y-212217D02*
X657093Y-211817D01*
X657493D01*
X657093Y-211417D01*
X657493Y-211017D01*
X657093D01*
X656693Y-210617D01*
X656293Y-211017D01*
X655893D01*
X656293Y-211417D01*
X655893Y-211817D01*
X656293D01*
X656693Y-212217D01*
Y-211817D02*
X656893Y-211617D01*
X657093D01*
X656893Y-211417D01*
X657093Y-211217D01*
X656893D01*
X656693Y-211017D01*
X656493Y-211217D01*
X656293D01*
X656493Y-211417D01*
X656293Y-211617D01*
X656493D01*
X656693Y-211817D01*
X658661Y-212217D02*
X659061Y-211817D01*
X659461D01*
X659061Y-211417D01*
X659461Y-211017D01*
X659061D01*
X658661Y-210617D01*
X658261Y-211017D01*
X657861D01*
X658261Y-211417D01*
X657861Y-211817D01*
X658261D01*
X658661Y-212217D01*
Y-211817D02*
X658861Y-211617D01*
X659061D01*
X658861Y-211417D01*
X659061Y-211217D01*
X658861D01*
X658661Y-211017D01*
X658461Y-211217D01*
X658261D01*
X658461Y-211417D01*
X658261Y-211617D01*
X658461D01*
X658661Y-211817D01*
X654724Y-209068D02*
X655124Y-208668D01*
X655524D01*
X655124Y-208268D01*
X655524Y-207868D01*
X655124D01*
X654724Y-207468D01*
X654324Y-207868D01*
X653924D01*
X654324Y-208268D01*
X653924Y-208668D01*
X654324D01*
X654724Y-209068D01*
Y-208668D02*
X654924Y-208468D01*
X655124D01*
X654924Y-208268D01*
X655124Y-208068D01*
X654924D01*
X654724Y-207868D01*
X654524Y-208068D01*
X654324D01*
X654524Y-208268D01*
X654324Y-208468D01*
X654524D01*
X654724Y-208668D01*
X656693Y-209068D02*
X657093Y-208668D01*
X657493D01*
X657093Y-208268D01*
X657493Y-207868D01*
X657093D01*
X656693Y-207468D01*
X656293Y-207868D01*
X655893D01*
X656293Y-208268D01*
X655893Y-208668D01*
X656293D01*
X656693Y-209068D01*
Y-208668D02*
X656893Y-208468D01*
X657093D01*
X656893Y-208268D01*
X657093Y-208068D01*
X656893D01*
X656693Y-207868D01*
X656493Y-208068D01*
X656293D01*
X656493Y-208268D01*
X656293Y-208468D01*
X656493D01*
X656693Y-208668D01*
X658661Y-209068D02*
X659061Y-208668D01*
X659461D01*
X659061Y-208268D01*
X659461Y-207868D01*
X659061D01*
X658661Y-207468D01*
X658261Y-207868D01*
X657861D01*
X658261Y-208268D01*
X657861Y-208668D01*
X658261D01*
X658661Y-209068D01*
Y-208668D02*
X658861Y-208468D01*
X659061D01*
X658861Y-208268D01*
X659061Y-208068D01*
X658861D01*
X658661Y-207868D01*
X658461Y-208068D01*
X658261D01*
X658461Y-208268D01*
X658261Y-208468D01*
X658461D01*
X658661Y-208668D01*
X675591Y-299619D02*
X675990Y-299219D01*
X676391D01*
X675990Y-298819D01*
X676391Y-298419D01*
X675990D01*
X675591Y-298019D01*
X675190Y-298419D01*
X674790D01*
X675190Y-298819D01*
X674790Y-299219D01*
X675190D01*
X675591Y-299619D01*
Y-299219D02*
X675791Y-299019D01*
X675990D01*
X675791Y-298819D01*
X675990Y-298619D01*
X675791D01*
X675591Y-298419D01*
X675390Y-298619D01*
X675190D01*
X675390Y-298819D01*
X675190Y-299019D01*
X675390D01*
X675591Y-299219D01*
X673622Y-299619D02*
X674022Y-299219D01*
X674422D01*
X674022Y-298819D01*
X674422Y-298419D01*
X674022D01*
X673622Y-298019D01*
X673222Y-298419D01*
X672822D01*
X673222Y-298819D01*
X672822Y-299219D01*
X673222D01*
X673622Y-299619D01*
Y-299219D02*
X673822Y-299019D01*
X674022D01*
X673822Y-298819D01*
X674022Y-298619D01*
X673822D01*
X673622Y-298419D01*
X673422Y-298619D01*
X673222D01*
X673422Y-298819D01*
X673222Y-299019D01*
X673422D01*
X673622Y-299219D01*
X671654Y-299619D02*
X672053Y-299219D01*
X672453D01*
X672053Y-298819D01*
X672453Y-298419D01*
X672053D01*
X671654Y-298019D01*
X671253Y-298419D01*
X670854D01*
X671253Y-298819D01*
X670854Y-299219D01*
X671253D01*
X671654Y-299619D01*
Y-299219D02*
X671853Y-299019D01*
X672053D01*
X671853Y-298819D01*
X672053Y-298619D01*
X671853D01*
X671654Y-298419D01*
X671454Y-298619D01*
X671253D01*
X671454Y-298819D01*
X671253Y-299019D01*
X671454D01*
X671654Y-299219D01*
X675591Y-302768D02*
X675990Y-302368D01*
X676391D01*
X675990Y-301969D01*
X676391Y-301569D01*
X675990D01*
X675591Y-301168D01*
X675190Y-301569D01*
X674790D01*
X675190Y-301969D01*
X674790Y-302368D01*
X675190D01*
X675591Y-302768D01*
Y-302368D02*
X675791Y-302168D01*
X675990D01*
X675791Y-301969D01*
X675990Y-301768D01*
X675791D01*
X675591Y-301569D01*
X675390Y-301768D01*
X675190D01*
X675390Y-301969D01*
X675190Y-302168D01*
X675390D01*
X675591Y-302368D01*
X673622Y-302768D02*
X674022Y-302368D01*
X674422D01*
X674022Y-301969D01*
X674422Y-301569D01*
X674022D01*
X673622Y-301168D01*
X673222Y-301569D01*
X672822D01*
X673222Y-301969D01*
X672822Y-302368D01*
X673222D01*
X673622Y-302768D01*
Y-302368D02*
X673822Y-302168D01*
X674022D01*
X673822Y-301969D01*
X674022Y-301768D01*
X673822D01*
X673622Y-301569D01*
X673422Y-301768D01*
X673222D01*
X673422Y-301969D01*
X673222Y-302168D01*
X673422D01*
X673622Y-302368D01*
X671654Y-302768D02*
X672053Y-302368D01*
X672453D01*
X672053Y-301969D01*
X672453Y-301569D01*
X672053D01*
X671654Y-301168D01*
X671253Y-301569D01*
X670854D01*
X671253Y-301969D01*
X670854Y-302368D01*
X671253D01*
X671654Y-302768D01*
Y-302368D02*
X671853Y-302168D01*
X672053D01*
X671853Y-301969D01*
X672053Y-301768D01*
X671853D01*
X671654Y-301569D01*
X671454Y-301768D01*
X671253D01*
X671454Y-301969D01*
X671253Y-302168D01*
X671454D01*
X671654Y-302368D01*
X157480Y-359461D02*
X157880Y-359061D01*
X158280D01*
X157880Y-358661D01*
X158280Y-358261D01*
X157880D01*
X157480Y-357861D01*
X157080Y-358261D01*
X156680D01*
X157080Y-358661D01*
X156680Y-359061D01*
X157080D01*
X157480Y-359461D01*
Y-359061D02*
X157680Y-358861D01*
X157880D01*
X157680Y-358661D01*
X157880Y-358461D01*
X157680D01*
X157480Y-358261D01*
X157280Y-358461D01*
X157080D01*
X157280Y-358661D01*
X157080Y-358861D01*
X157280D01*
X157480Y-359061D01*
X155512Y-359461D02*
X155912Y-359061D01*
X156312D01*
X155912Y-358661D01*
X156312Y-358261D01*
X155912D01*
X155512Y-357861D01*
X155112Y-358261D01*
X154712D01*
X155112Y-358661D01*
X154712Y-359061D01*
X155112D01*
X155512Y-359461D01*
Y-359061D02*
X155712Y-358861D01*
X155912D01*
X155712Y-358661D01*
X155912Y-358461D01*
X155712D01*
X155512Y-358261D01*
X155312Y-358461D01*
X155112D01*
X155312Y-358661D01*
X155112Y-358861D01*
X155312D01*
X155512Y-359061D01*
X153543Y-359461D02*
X153943Y-359061D01*
X154343D01*
X153943Y-358661D01*
X154343Y-358261D01*
X153943D01*
X153543Y-357861D01*
X153143Y-358261D01*
X152743D01*
X153143Y-358661D01*
X152743Y-359061D01*
X153143D01*
X153543Y-359461D01*
Y-359061D02*
X153743Y-358861D01*
X153943D01*
X153743Y-358661D01*
X153943Y-358461D01*
X153743D01*
X153543Y-358261D01*
X153343Y-358461D01*
X153143D01*
X153343Y-358661D01*
X153143Y-358861D01*
X153343D01*
X153543Y-359061D01*
X157480Y-362611D02*
X157880Y-362211D01*
X158280D01*
X157880Y-361811D01*
X158280Y-361411D01*
X157880D01*
X157480Y-361011D01*
X157080Y-361411D01*
X156680D01*
X157080Y-361811D01*
X156680Y-362211D01*
X157080D01*
X157480Y-362611D01*
Y-362211D02*
X157680Y-362011D01*
X157880D01*
X157680Y-361811D01*
X157880Y-361611D01*
X157680D01*
X157480Y-361411D01*
X157280Y-361611D01*
X157080D01*
X157280Y-361811D01*
X157080Y-362011D01*
X157280D01*
X157480Y-362211D01*
X155512Y-362611D02*
X155912Y-362211D01*
X156312D01*
X155912Y-361811D01*
X156312Y-361411D01*
X155912D01*
X155512Y-361011D01*
X155112Y-361411D01*
X154712D01*
X155112Y-361811D01*
X154712Y-362211D01*
X155112D01*
X155512Y-362611D01*
Y-362211D02*
X155712Y-362011D01*
X155912D01*
X155712Y-361811D01*
X155912Y-361611D01*
X155712D01*
X155512Y-361411D01*
X155312Y-361611D01*
X155112D01*
X155312Y-361811D01*
X155112Y-362011D01*
X155312D01*
X155512Y-362211D01*
X153543Y-362611D02*
X153943Y-362211D01*
X154343D01*
X153943Y-361811D01*
X154343Y-361411D01*
X153943D01*
X153543Y-361011D01*
X153143Y-361411D01*
X152743D01*
X153143Y-361811D01*
X152743Y-362211D01*
X153143D01*
X153543Y-362611D01*
Y-362211D02*
X153743Y-362011D01*
X153943D01*
X153743Y-361811D01*
X153943Y-361611D01*
X153743D01*
X153543Y-361411D01*
X153343Y-361611D01*
X153143D01*
X153343Y-361811D01*
X153143Y-362011D01*
X153343D01*
X153543Y-362211D01*
X154724Y-390416D02*
X155124Y-390016D01*
X155524D01*
X155124Y-389616D01*
X155524Y-389216D01*
X155124D01*
X154724Y-388816D01*
X154324Y-389216D01*
X153924D01*
X154324Y-389616D01*
X153924Y-390016D01*
X154324D01*
X154724Y-390416D01*
Y-390016D02*
X154924Y-389816D01*
X155124D01*
X154924Y-389616D01*
X155124Y-389416D01*
X154924D01*
X154724Y-389216D01*
X154524Y-389416D01*
X154324D01*
X154524Y-389616D01*
X154324Y-389816D01*
X154524D01*
X154724Y-390016D01*
X156693Y-390416D02*
X157093Y-390016D01*
X157493D01*
X157093Y-389616D01*
X157493Y-389216D01*
X157093D01*
X156693Y-388816D01*
X156293Y-389216D01*
X155893D01*
X156293Y-389616D01*
X155893Y-390016D01*
X156293D01*
X156693Y-390416D01*
Y-390016D02*
X156893Y-389816D01*
X157093D01*
X156893Y-389616D01*
X157093Y-389416D01*
X156893D01*
X156693Y-389216D01*
X156493Y-389416D01*
X156293D01*
X156493Y-389616D01*
X156293Y-389816D01*
X156493D01*
X156693Y-390016D01*
X158661Y-390416D02*
X159061Y-390016D01*
X159461D01*
X159061Y-389616D01*
X159461Y-389216D01*
X159061D01*
X158661Y-388816D01*
X158261Y-389216D01*
X157861D01*
X158261Y-389616D01*
X157861Y-390016D01*
X158261D01*
X158661Y-390416D01*
Y-390016D02*
X158861Y-389816D01*
X159061D01*
X158861Y-389616D01*
X159061Y-389416D01*
X158861D01*
X158661Y-389216D01*
X158461Y-389416D01*
X158261D01*
X158461Y-389616D01*
X158261Y-389816D01*
X158461D01*
X158661Y-390016D01*
X154724Y-387266D02*
X155124Y-386866D01*
X155524D01*
X155124Y-386466D01*
X155524Y-386066D01*
X155124D01*
X154724Y-385666D01*
X154324Y-386066D01*
X153924D01*
X154324Y-386466D01*
X153924Y-386866D01*
X154324D01*
X154724Y-387266D01*
Y-386866D02*
X154924Y-386666D01*
X155124D01*
X154924Y-386466D01*
X155124Y-386266D01*
X154924D01*
X154724Y-386066D01*
X154524Y-386266D01*
X154324D01*
X154524Y-386466D01*
X154324Y-386666D01*
X154524D01*
X154724Y-386866D01*
X156693Y-387266D02*
X157093Y-386866D01*
X157493D01*
X157093Y-386466D01*
X157493Y-386066D01*
X157093D01*
X156693Y-385666D01*
X156293Y-386066D01*
X155893D01*
X156293Y-386466D01*
X155893Y-386866D01*
X156293D01*
X156693Y-387266D01*
Y-386866D02*
X156893Y-386666D01*
X157093D01*
X156893Y-386466D01*
X157093Y-386266D01*
X156893D01*
X156693Y-386066D01*
X156493Y-386266D01*
X156293D01*
X156493Y-386466D01*
X156293Y-386666D01*
X156493D01*
X156693Y-386866D01*
X158661Y-387266D02*
X159061Y-386866D01*
X159461D01*
X159061Y-386466D01*
X159461Y-386066D01*
X159061D01*
X158661Y-385666D01*
X158261Y-386066D01*
X157861D01*
X158261Y-386466D01*
X157861Y-386866D01*
X158261D01*
X158661Y-387266D01*
Y-386866D02*
X158861Y-386666D01*
X159061D01*
X158861Y-386466D01*
X159061Y-386266D01*
X158861D01*
X158661Y-386066D01*
X158461Y-386266D01*
X158261D01*
X158461Y-386466D01*
X158261Y-386666D01*
X158461D01*
X158661Y-386866D01*
X575919Y-237705D02*
X576319Y-237305D01*
X576719D01*
X576319Y-236906D01*
X576719Y-236506D01*
X576319D01*
X575919Y-236105D01*
X575519Y-236506D01*
X575119D01*
X575519Y-236906D01*
X575119Y-237305D01*
X575519D01*
X575919Y-237705D01*
Y-237305D02*
X576119Y-237105D01*
X576319D01*
X576119Y-236906D01*
X576319Y-236705D01*
X576119D01*
X575919Y-236506D01*
X575719Y-236705D01*
X575519D01*
X575719Y-236906D01*
X575519Y-237105D01*
X575719D01*
X575919Y-237305D01*
X596702Y-248241D02*
X597102Y-247841D01*
X597502D01*
X597102Y-247441D01*
X597502Y-247041D01*
X597102D01*
X596702Y-246641D01*
X596302Y-247041D01*
X595902D01*
X596302Y-247441D01*
X595902Y-247841D01*
X596302D01*
X596702Y-248241D01*
Y-247841D02*
X596902Y-247641D01*
X597102D01*
X596902Y-247441D01*
X597102Y-247241D01*
X596902D01*
X596702Y-247041D01*
X596502Y-247241D01*
X596302D01*
X596502Y-247441D01*
X596302Y-247641D01*
X596502D01*
X596702Y-247841D01*
X591978Y-248241D02*
X592378Y-247841D01*
X592778D01*
X592378Y-247441D01*
X592778Y-247041D01*
X592378D01*
X591978Y-246641D01*
X591578Y-247041D01*
X591178D01*
X591578Y-247441D01*
X591178Y-247841D01*
X591578D01*
X591978Y-248241D01*
Y-247841D02*
X592178Y-247641D01*
X592378D01*
X592178Y-247441D01*
X592378Y-247241D01*
X592178D01*
X591978Y-247041D01*
X591778Y-247241D01*
X591578D01*
X591778Y-247441D01*
X591578Y-247641D01*
X591778D01*
X591978Y-247841D01*
X586466Y-248241D02*
X586866Y-247841D01*
X587266D01*
X586866Y-247441D01*
X587266Y-247041D01*
X586866D01*
X586466Y-246641D01*
X586066Y-247041D01*
X585666D01*
X586066Y-247441D01*
X585666Y-247841D01*
X586066D01*
X586466Y-248241D01*
Y-247841D02*
X586666Y-247641D01*
X586866D01*
X586666Y-247441D01*
X586866Y-247241D01*
X586666D01*
X586466Y-247041D01*
X586266Y-247241D01*
X586066D01*
X586266Y-247441D01*
X586066Y-247641D01*
X586266D01*
X586466Y-247841D01*
X580954Y-207989D02*
X581354Y-207589D01*
X581754D01*
X581354Y-207189D01*
X581754Y-206789D01*
X581354D01*
X580954Y-206389D01*
X580554Y-206789D01*
X580154D01*
X580554Y-207189D01*
X580154Y-207589D01*
X580554D01*
X580954Y-207989D01*
Y-207589D02*
X581154Y-207389D01*
X581354D01*
X581154Y-207189D01*
X581354Y-206989D01*
X581154D01*
X580954Y-206789D01*
X580754Y-206989D01*
X580554D01*
X580754Y-207189D01*
X580554Y-207389D01*
X580754D01*
X580954Y-207589D01*
X580935Y-238212D02*
X581335Y-237812D01*
X581735D01*
X581335Y-237412D01*
X581735Y-237012D01*
X581335D01*
X580935Y-236612D01*
X580535Y-237012D01*
X580135D01*
X580535Y-237412D01*
X580135Y-237812D01*
X580535D01*
X580935Y-238212D01*
Y-237812D02*
X581135Y-237612D01*
X581335D01*
X581135Y-237412D01*
X581335Y-237212D01*
X581135D01*
X580935Y-237012D01*
X580735Y-237212D01*
X580535D01*
X580735Y-237412D01*
X580535Y-237612D01*
X580735D01*
X580935Y-237812D01*
X554519Y-213689D02*
X554919Y-213289D01*
X555319D01*
X554919Y-212889D01*
X555319Y-212489D01*
X554919D01*
X554519Y-212089D01*
X554119Y-212489D01*
X553719D01*
X554119Y-212889D01*
X553719Y-213289D01*
X554119D01*
X554519Y-213689D01*
Y-213289D02*
X554719Y-213089D01*
X554919D01*
X554719Y-212889D01*
X554919Y-212689D01*
X554719D01*
X554519Y-212489D01*
X554319Y-212689D01*
X554119D01*
X554319Y-212889D01*
X554119Y-213089D01*
X554319D01*
X554519Y-213289D01*
X546419Y-246905D02*
X546819Y-246505D01*
X547219D01*
X546819Y-246106D01*
X547219Y-245706D01*
X546819D01*
X546419Y-245305D01*
X546019Y-245706D01*
X545619D01*
X546019Y-246106D01*
X545619Y-246505D01*
X546019D01*
X546419Y-246905D01*
Y-246505D02*
X546619Y-246305D01*
X546819D01*
X546619Y-246106D01*
X546819Y-245905D01*
X546619D01*
X546419Y-245706D01*
X546219Y-245905D01*
X546019D01*
X546219Y-246106D01*
X546019Y-246305D01*
X546219D01*
X546419Y-246505D01*
X626819Y-244806D02*
X627219Y-244406D01*
X627619D01*
X627219Y-244005D01*
X627619Y-243605D01*
X627219D01*
X626819Y-243205D01*
X626419Y-243605D01*
X626019D01*
X626419Y-244005D01*
X626019Y-244406D01*
X626419D01*
X626819Y-244806D01*
Y-244406D02*
X627019Y-244205D01*
X627219D01*
X627019Y-244005D01*
X627219Y-243806D01*
X627019D01*
X626819Y-243605D01*
X626619Y-243806D01*
X626419D01*
X626619Y-244005D01*
X626419Y-244205D01*
X626619D01*
X626819Y-244406D01*
X611094Y-248910D02*
X611494Y-248510D01*
X611894D01*
X611494Y-248110D01*
X611894Y-247710D01*
X611494D01*
X611094Y-247310D01*
X610694Y-247710D01*
X610294D01*
X610694Y-248110D01*
X610294Y-248510D01*
X610694D01*
X611094Y-248910D01*
Y-248510D02*
X611294Y-248310D01*
X611494D01*
X611294Y-248110D01*
X611494Y-247910D01*
X611294D01*
X611094Y-247710D01*
X610894Y-247910D01*
X610694D01*
X610894Y-248110D01*
X610694Y-248310D01*
X610894D01*
X611094Y-248510D01*
X603002Y-248241D02*
X603402Y-247841D01*
X603802D01*
X603402Y-247441D01*
X603802Y-247041D01*
X603402D01*
X603002Y-246641D01*
X602602Y-247041D01*
X602202D01*
X602602Y-247441D01*
X602202Y-247841D01*
X602602D01*
X603002Y-248241D01*
Y-247841D02*
X603202Y-247641D01*
X603402D01*
X603202Y-247441D01*
X603402Y-247241D01*
X603202D01*
X603002Y-247041D01*
X602802Y-247241D01*
X602602D01*
X602802Y-247441D01*
X602602Y-247641D01*
X602802D01*
X603002Y-247841D01*
X531496Y-263447D02*
X531896Y-263047D01*
X532296D01*
X531896Y-262647D01*
X532296Y-262247D01*
X531896D01*
X531496Y-261847D01*
X531096Y-262247D01*
X530696D01*
X531096Y-262647D01*
X530696Y-263047D01*
X531096D01*
X531496Y-263447D01*
Y-263047D02*
X531696Y-262847D01*
X531896D01*
X531696Y-262647D01*
X531896Y-262447D01*
X531696D01*
X531496Y-262247D01*
X531296Y-262447D01*
X531096D01*
X531296Y-262647D01*
X531096Y-262847D01*
X531296D01*
X531496Y-263047D01*
X461811Y-311479D02*
X462211Y-311079D01*
X462611D01*
X462211Y-310679D01*
X462611Y-310279D01*
X462211D01*
X461811Y-309879D01*
X461411Y-310279D01*
X461011D01*
X461411Y-310679D01*
X461011Y-311079D01*
X461411D01*
X461811Y-311479D01*
Y-311079D02*
X462011Y-310879D01*
X462211D01*
X462011Y-310679D01*
X462211Y-310479D01*
X462011D01*
X461811Y-310279D01*
X461611Y-310479D01*
X461411D01*
X461611Y-310679D01*
X461411Y-310879D01*
X461611D01*
X461811Y-311079D01*
X450000Y-294550D02*
X450400Y-294150D01*
X450800D01*
X450400Y-293750D01*
X450800Y-293350D01*
X450400D01*
X450000Y-292950D01*
X449600Y-293350D01*
X449200D01*
X449600Y-293750D01*
X449200Y-294150D01*
X449600D01*
X450000Y-294550D01*
Y-294150D02*
X450200Y-293950D01*
X450400D01*
X450200Y-293750D01*
X450400Y-293550D01*
X450200D01*
X450000Y-293350D01*
X449800Y-293550D01*
X449600D01*
X449800Y-293750D01*
X449600Y-293950D01*
X449800D01*
X450000Y-294150D01*
X422441Y-294589D02*
X422841Y-294189D01*
X423241D01*
X422841Y-293789D01*
X423241Y-293389D01*
X422841D01*
X422441Y-292989D01*
X422041Y-293389D01*
X421641D01*
X422041Y-293789D01*
X421641Y-294189D01*
X422041D01*
X422441Y-294589D01*
Y-294189D02*
X422641Y-293989D01*
X422841D01*
X422641Y-293789D01*
X422841Y-293589D01*
X422641D01*
X422441Y-293389D01*
X422241Y-293589D01*
X422041D01*
X422241Y-293789D01*
X422041Y-293989D01*
X422241D01*
X422441Y-294189D01*
X531496Y-214235D02*
X531896Y-213835D01*
X532296D01*
X531896Y-213435D01*
X532296Y-213035D01*
X531896D01*
X531496Y-212635D01*
X531096Y-213035D01*
X530696D01*
X531096Y-213435D01*
X530696Y-213835D01*
X531096D01*
X531496Y-214235D01*
Y-213835D02*
X531696Y-213635D01*
X531896D01*
X531696Y-213435D01*
X531896Y-213235D01*
X531696D01*
X531496Y-213035D01*
X531296Y-213235D01*
X531096D01*
X531296Y-213435D01*
X531096Y-213635D01*
X531296D01*
X531496Y-213835D01*
X338525Y-244367D02*
X338925Y-243967D01*
X339325D01*
X338925Y-243567D01*
X339325Y-243167D01*
X338925D01*
X338525Y-242767D01*
X338125Y-243167D01*
X337725D01*
X338125Y-243567D01*
X337725Y-243967D01*
X338125D01*
X338525Y-244367D01*
Y-243967D02*
X338725Y-243767D01*
X338925D01*
X338725Y-243567D01*
X338925Y-243367D01*
X338725D01*
X338525Y-243167D01*
X338325Y-243367D01*
X338125D01*
X338325Y-243567D01*
X338125Y-243767D01*
X338325D01*
X338525Y-243967D01*
X525591Y-233888D02*
X525991Y-233488D01*
X526391D01*
X525991Y-233088D01*
X526391Y-232688D01*
X525991D01*
X525591Y-232288D01*
X525191Y-232688D01*
X524791D01*
X525191Y-233088D01*
X524791Y-233488D01*
X525191D01*
X525591Y-233888D01*
Y-233488D02*
X525791Y-233288D01*
X525991D01*
X525791Y-233088D01*
X525991Y-232888D01*
X525791D01*
X525591Y-232688D01*
X525391Y-232888D01*
X525191D01*
X525391Y-233088D01*
X525191Y-233288D01*
X525391D01*
X525591Y-233488D01*
X439697Y-163349D02*
X440097Y-162949D01*
X440497D01*
X440097Y-162549D01*
X440497Y-162149D01*
X440097D01*
X439697Y-161749D01*
X439297Y-162149D01*
X438897D01*
X439297Y-162549D01*
X438897Y-162949D01*
X439297D01*
X439697Y-163349D01*
Y-162949D02*
X439897Y-162749D01*
X440097D01*
X439897Y-162549D01*
X440097Y-162349D01*
X439897D01*
X439697Y-162149D01*
X439497Y-162349D01*
X439297D01*
X439497Y-162549D01*
X439297Y-162749D01*
X439497D01*
X439697Y-162949D01*
X343144Y-225973D02*
X343544Y-225573D01*
X343944D01*
X343544Y-225173D01*
X343944Y-224773D01*
X343544D01*
X343144Y-224373D01*
X342744Y-224773D01*
X342344D01*
X342744Y-225173D01*
X342344Y-225573D01*
X342744D01*
X343144Y-225973D01*
Y-225573D02*
X343344Y-225373D01*
X343544D01*
X343344Y-225173D01*
X343544Y-224973D01*
X343344D01*
X343144Y-224773D01*
X342944Y-224973D01*
X342744D01*
X342944Y-225173D01*
X342744Y-225373D01*
X342944D01*
X343144Y-225573D01*
X420669Y-158723D02*
X421069Y-158323D01*
X421469D01*
X421069Y-157923D01*
X421469Y-157523D01*
X421069D01*
X420669Y-157123D01*
X420269Y-157523D01*
X419869D01*
X420269Y-157923D01*
X419869Y-158323D01*
X420269D01*
X420669Y-158723D01*
Y-158323D02*
X420869Y-158123D01*
X421069D01*
X420869Y-157923D01*
X421069Y-157723D01*
X420869D01*
X420669Y-157523D01*
X420469Y-157723D01*
X420269D01*
X420469Y-157923D01*
X420269Y-158123D01*
X420469D01*
X420669Y-158323D01*
X531496Y-224077D02*
X531896Y-223677D01*
X532296D01*
X531896Y-223277D01*
X532296Y-222877D01*
X531896D01*
X531496Y-222477D01*
X531096Y-222877D01*
X530696D01*
X531096Y-223277D01*
X530696Y-223677D01*
X531096D01*
X531496Y-224077D01*
Y-223677D02*
X531696Y-223477D01*
X531896D01*
X531696Y-223277D01*
X531896Y-223077D01*
X531696D01*
X531496Y-222877D01*
X531296Y-223077D01*
X531096D01*
X531296Y-223277D01*
X531096Y-223477D01*
X531296D01*
X531496Y-223677D01*
X338583Y-236036D02*
X338983Y-235636D01*
X339383D01*
X338983Y-235236D01*
X339383Y-234836D01*
X338983D01*
X338583Y-234436D01*
X338183Y-234836D01*
X337783D01*
X338183Y-235236D01*
X337783Y-235636D01*
X338183D01*
X338583Y-236036D01*
Y-235636D02*
X338783Y-235436D01*
X338983D01*
X338783Y-235236D01*
X338983Y-235036D01*
X338783D01*
X338583Y-234836D01*
X338383Y-235036D01*
X338183D01*
X338383Y-235236D01*
X338183Y-235436D01*
X338383D01*
X338583Y-235636D01*
X525591Y-243762D02*
X525991Y-243362D01*
X526391D01*
X525991Y-242962D01*
X526391Y-242562D01*
X525991D01*
X525591Y-242162D01*
X525191Y-242562D01*
X524791D01*
X525191Y-242962D01*
X524791Y-243362D01*
X525191D01*
X525591Y-243762D01*
Y-243362D02*
X525791Y-243162D01*
X525991D01*
X525791Y-242962D01*
X525991Y-242762D01*
X525791D01*
X525591Y-242562D01*
X525391Y-242762D01*
X525191D01*
X525391Y-242962D01*
X525191Y-243162D01*
X525391D01*
X525591Y-243362D01*
X430150Y-163054D02*
X430550Y-162654D01*
X430950D01*
X430550Y-162253D01*
X430950Y-161854D01*
X430550D01*
X430150Y-161453D01*
X429750Y-161854D01*
X429350D01*
X429750Y-162253D01*
X429350Y-162654D01*
X429750D01*
X430150Y-163054D01*
Y-162654D02*
X430350Y-162453D01*
X430550D01*
X430350Y-162253D01*
X430550Y-162054D01*
X430350D01*
X430150Y-161854D01*
X429950Y-162054D01*
X429750D01*
X429950Y-162253D01*
X429750Y-162453D01*
X429950D01*
X430150Y-162654D01*
X343444Y-216173D02*
X343844Y-215773D01*
X344244D01*
X343844Y-215373D01*
X344244Y-214973D01*
X343844D01*
X343444Y-214573D01*
X343044Y-214973D01*
X342644D01*
X343044Y-215373D01*
X342644Y-215773D01*
X343044D01*
X343444Y-216173D01*
Y-215773D02*
X343644Y-215573D01*
X343844D01*
X343644Y-215373D01*
X343844Y-215173D01*
X343644D01*
X343444Y-214973D01*
X343244Y-215173D01*
X343044D01*
X343244Y-215373D01*
X343044Y-215573D01*
X343244D01*
X343444Y-215773D01*
X432283Y-294550D02*
X432684Y-294150D01*
X433083D01*
X432684Y-293750D01*
X433083Y-293350D01*
X432684D01*
X432283Y-292950D01*
X431883Y-293350D01*
X431484D01*
X431883Y-293750D01*
X431484Y-294150D01*
X431883D01*
X432283Y-294550D01*
Y-294150D02*
X432483Y-293950D01*
X432684D01*
X432483Y-293750D01*
X432684Y-293550D01*
X432483D01*
X432283Y-293350D01*
X432084Y-293550D01*
X431883D01*
X432084Y-293750D01*
X431883Y-293950D01*
X432084D01*
X432283Y-294150D01*
X410528Y-158723D02*
X410928Y-158323D01*
X411328D01*
X410928Y-157923D01*
X411328Y-157523D01*
X410928D01*
X410528Y-157123D01*
X410128Y-157523D01*
X409728D01*
X410128Y-157923D01*
X409728Y-158323D01*
X410128D01*
X410528Y-158723D01*
Y-158323D02*
X410728Y-158123D01*
X410928D01*
X410728Y-157923D01*
X410928Y-157723D01*
X410728D01*
X410528Y-157523D01*
X410328Y-157723D01*
X410128D01*
X410328Y-157923D01*
X410128Y-158123D01*
X410328D01*
X410528Y-158323D01*
X342944Y-265273D02*
X343344Y-264873D01*
X343744D01*
X343344Y-264473D01*
X343744Y-264073D01*
X343344D01*
X342944Y-263673D01*
X342544Y-264073D01*
X342144D01*
X342544Y-264473D01*
X342144Y-264873D01*
X342544D01*
X342944Y-265273D01*
Y-264873D02*
X343144Y-264673D01*
X343344D01*
X343144Y-264473D01*
X343344Y-264273D01*
X343144D01*
X342944Y-264073D01*
X342744Y-264273D01*
X342544D01*
X342744Y-264473D01*
X342544Y-264673D01*
X342744D01*
X342944Y-264873D01*
X444095Y-294550D02*
X444494Y-294150D01*
X444895D01*
X444494Y-293750D01*
X444895Y-293350D01*
X444494D01*
X444095Y-292950D01*
X443694Y-293350D01*
X443294D01*
X443694Y-293750D01*
X443294Y-294150D01*
X443694D01*
X444095Y-294550D01*
Y-294150D02*
X444295Y-293950D01*
X444494D01*
X444295Y-293750D01*
X444494Y-293550D01*
X444295D01*
X444095Y-293350D01*
X443894Y-293550D01*
X443694D01*
X443894Y-293750D01*
X443694Y-293950D01*
X443894D01*
X444095Y-294150D01*
X422835Y-311872D02*
X423235Y-311472D01*
X423635D01*
X423235Y-311072D01*
X423635Y-310672D01*
X423235D01*
X422835Y-310272D01*
X422435Y-310672D01*
X422035D01*
X422435Y-311072D01*
X422035Y-311472D01*
X422435D01*
X422835Y-311872D01*
Y-311472D02*
X423035Y-311272D01*
X423235D01*
X423035Y-311072D01*
X423235Y-310872D01*
X423035D01*
X422835Y-310672D01*
X422635Y-310872D01*
X422435D01*
X422635Y-311072D01*
X422435Y-311272D01*
X422635D01*
X422835Y-311472D01*
X531496Y-233888D02*
X531896Y-233488D01*
X532296D01*
X531896Y-233088D01*
X532296Y-232688D01*
X531896D01*
X531496Y-232288D01*
X531096Y-232688D01*
X530696D01*
X531096Y-233088D01*
X530696Y-233488D01*
X531096D01*
X531496Y-233888D01*
Y-233488D02*
X531696Y-233288D01*
X531896D01*
X531696Y-233088D01*
X531896Y-232888D01*
X531696D01*
X531496Y-232688D01*
X531296Y-232888D01*
X531096D01*
X531296Y-233088D01*
X531096Y-233288D01*
X531296D01*
X531496Y-233488D01*
X430150Y-158723D02*
X430550Y-158323D01*
X430950D01*
X430550Y-157923D01*
X430950Y-157523D01*
X430550D01*
X430150Y-157123D01*
X429750Y-157523D01*
X429350D01*
X429750Y-157923D01*
X429350Y-158323D01*
X429750D01*
X430150Y-158723D01*
Y-158323D02*
X430350Y-158123D01*
X430550D01*
X430350Y-157923D01*
X430550Y-157723D01*
X430350D01*
X430150Y-157523D01*
X429950Y-157723D01*
X429750D01*
X429950Y-157923D01*
X429750Y-158123D01*
X429950D01*
X430150Y-158323D01*
X338444Y-225973D02*
X338844Y-225573D01*
X339244D01*
X338844Y-225173D01*
X339244Y-224773D01*
X338844D01*
X338444Y-224373D01*
X338044Y-224773D01*
X337644D01*
X338044Y-225173D01*
X337644Y-225573D01*
X338044D01*
X338444Y-225973D01*
Y-225573D02*
X338644Y-225373D01*
X338844D01*
X338644Y-225173D01*
X338844Y-224973D01*
X338644D01*
X338444Y-224773D01*
X338244Y-224973D01*
X338044D01*
X338244Y-225173D01*
X338044Y-225373D01*
X338244D01*
X338444Y-225573D01*
X402756Y-311872D02*
X403156Y-311472D01*
X403556D01*
X403156Y-311072D01*
X403556Y-310672D01*
X403156D01*
X402756Y-310272D01*
X402356Y-310672D01*
X401956D01*
X402356Y-311072D01*
X401956Y-311472D01*
X402356D01*
X402756Y-311872D01*
Y-311472D02*
X402956Y-311272D01*
X403156D01*
X402956Y-311072D01*
X403156Y-310872D01*
X402956D01*
X402756Y-310672D01*
X402556Y-310872D01*
X402356D01*
X402556Y-311072D01*
X402356Y-311272D01*
X402556D01*
X402756Y-311472D01*
X525591Y-254768D02*
X525991Y-254368D01*
X526391D01*
X525991Y-253969D01*
X526391Y-253569D01*
X525991D01*
X525591Y-253169D01*
X525191Y-253569D01*
X524791D01*
X525191Y-253969D01*
X524791Y-254368D01*
X525191D01*
X525591Y-254768D01*
Y-254368D02*
X525791Y-254169D01*
X525991D01*
X525791Y-253969D01*
X525991Y-253768D01*
X525791D01*
X525591Y-253569D01*
X525391Y-253768D01*
X525191D01*
X525391Y-253969D01*
X525191Y-254169D01*
X525391D01*
X525591Y-254368D01*
X420079Y-163349D02*
X420479Y-162949D01*
X420879D01*
X420479Y-162549D01*
X420879Y-162149D01*
X420479D01*
X420079Y-161749D01*
X419679Y-162149D01*
X419279D01*
X419679Y-162549D01*
X419279Y-162949D01*
X419679D01*
X420079Y-163349D01*
Y-162949D02*
X420279Y-162749D01*
X420479D01*
X420279Y-162549D01*
X420479Y-162349D01*
X420279D01*
X420079Y-162149D01*
X419879Y-162349D01*
X419679D01*
X419879Y-162549D01*
X419679Y-162749D01*
X419879D01*
X420079Y-162949D01*
X343403Y-206451D02*
X343803Y-206051D01*
X344203D01*
X343803Y-205651D01*
X344203Y-205251D01*
X343803D01*
X343403Y-204851D01*
X343003Y-205251D01*
X342603D01*
X343003Y-205651D01*
X342603Y-206051D01*
X343003D01*
X343403Y-206451D01*
Y-206051D02*
X343603Y-205851D01*
X343803D01*
X343603Y-205651D01*
X343803Y-205451D01*
X343603D01*
X343403Y-205251D01*
X343203Y-205451D01*
X343003D01*
X343203Y-205651D01*
X343003Y-205851D01*
X343203D01*
X343403Y-206051D01*
X525591Y-204392D02*
X525991Y-203992D01*
X526391D01*
X525991Y-203592D01*
X526391Y-203192D01*
X525991D01*
X525591Y-202792D01*
X525191Y-203192D01*
X524791D01*
X525191Y-203592D01*
X524791Y-203992D01*
X525191D01*
X525591Y-204392D01*
Y-203992D02*
X525791Y-203792D01*
X525991D01*
X525791Y-203592D01*
X525991Y-203392D01*
X525791D01*
X525591Y-203192D01*
X525391Y-203392D01*
X525191D01*
X525391Y-203592D01*
X525191Y-203792D01*
X525391D01*
X525591Y-203992D01*
X400295Y-158624D02*
X400695Y-158224D01*
X401095D01*
X400695Y-157824D01*
X401095Y-157424D01*
X400695D01*
X400295Y-157024D01*
X399895Y-157424D01*
X399495D01*
X399895Y-157824D01*
X399495Y-158224D01*
X399895D01*
X400295Y-158624D01*
Y-158224D02*
X400495Y-158024D01*
X400695D01*
X400495Y-157824D01*
X400695Y-157624D01*
X400495D01*
X400295Y-157424D01*
X400095Y-157624D01*
X399895D01*
X400095Y-157824D01*
X399895Y-158024D01*
X400095D01*
X400295Y-158224D01*
X343144Y-255573D02*
X343544Y-255173D01*
X343944D01*
X343544Y-254773D01*
X343944Y-254373D01*
X343544D01*
X343144Y-253973D01*
X342744Y-254373D01*
X342344D01*
X342744Y-254773D01*
X342344Y-255173D01*
X342744D01*
X343144Y-255573D01*
Y-255173D02*
X343344Y-254973D01*
X343544D01*
X343344Y-254773D01*
X343544Y-254573D01*
X343344D01*
X343144Y-254373D01*
X342944Y-254573D01*
X342744D01*
X342944Y-254773D01*
X342744Y-254973D01*
X342944D01*
X343144Y-255173D01*
X431928Y-311989D02*
X432328Y-311589D01*
X432728D01*
X432328Y-311189D01*
X432728Y-310789D01*
X432328D01*
X431928Y-310389D01*
X431528Y-310789D01*
X431128D01*
X431528Y-311189D01*
X431128Y-311589D01*
X431528D01*
X431928Y-311989D01*
Y-311589D02*
X432128Y-311389D01*
X432328D01*
X432128Y-311189D01*
X432328Y-310989D01*
X432128D01*
X431928Y-310789D01*
X431728Y-310989D01*
X431528D01*
X431728Y-311189D01*
X431528Y-311389D01*
X431728D01*
X431928Y-311589D01*
X531496Y-243762D02*
X531896Y-243362D01*
X532296D01*
X531896Y-242962D01*
X532296Y-242562D01*
X531896D01*
X531496Y-242162D01*
X531096Y-242562D01*
X530696D01*
X531096Y-242962D01*
X530696Y-243362D01*
X531096D01*
X531496Y-243762D01*
Y-243362D02*
X531696Y-243162D01*
X531896D01*
X531696Y-242962D01*
X531896Y-242762D01*
X531696D01*
X531496Y-242562D01*
X531296Y-242762D01*
X531096D01*
X531296Y-242962D01*
X531096Y-243162D01*
X531296D01*
X531496Y-243362D01*
X338844Y-216073D02*
X339244Y-215673D01*
X339644D01*
X339244Y-215273D01*
X339644Y-214873D01*
X339244D01*
X338844Y-214473D01*
X338444Y-214873D01*
X338044D01*
X338444Y-215273D01*
X338044Y-215673D01*
X338444D01*
X338844Y-216073D01*
Y-215673D02*
X339044Y-215473D01*
X339244D01*
X339044Y-215273D01*
X339244Y-215073D01*
X339044D01*
X338844Y-214873D01*
X338644Y-215073D01*
X338444D01*
X338644Y-215273D01*
X338444Y-215473D01*
X338644D01*
X338844Y-215673D01*
X402362Y-294550D02*
X402762Y-294150D01*
X403162D01*
X402762Y-293750D01*
X403162Y-293350D01*
X402762D01*
X402362Y-292950D01*
X401962Y-293350D01*
X401562D01*
X401962Y-293750D01*
X401562Y-294150D01*
X401962D01*
X402362Y-294550D01*
Y-294150D02*
X402562Y-293950D01*
X402762D01*
X402562Y-293750D01*
X402762Y-293550D01*
X402562D01*
X402362Y-293350D01*
X402162Y-293550D01*
X401962D01*
X402162Y-293750D01*
X401962Y-293950D01*
X402162D01*
X402362Y-294150D01*
X525591Y-263447D02*
X525991Y-263047D01*
X526391D01*
X525991Y-262647D01*
X526391Y-262247D01*
X525991D01*
X525591Y-261847D01*
X525191Y-262247D01*
X524791D01*
X525191Y-262647D01*
X524791Y-263047D01*
X525191D01*
X525591Y-263447D01*
Y-263047D02*
X525791Y-262847D01*
X525991D01*
X525791Y-262647D01*
X525991Y-262447D01*
X525791D01*
X525591Y-262247D01*
X525391Y-262447D01*
X525191D01*
X525391Y-262647D01*
X525191Y-262847D01*
X525391D01*
X525591Y-263047D01*
X410913Y-163558D02*
X411313Y-163157D01*
X411713D01*
X411313Y-162758D01*
X411713Y-162357D01*
X411313D01*
X410913Y-161958D01*
X410513Y-162357D01*
X410113D01*
X410513Y-162758D01*
X410113Y-163157D01*
X410513D01*
X410913Y-163558D01*
Y-163157D02*
X411113Y-162958D01*
X411313D01*
X411113Y-162758D01*
X411313Y-162557D01*
X411113D01*
X410913Y-162357D01*
X410713Y-162557D01*
X410513D01*
X410713Y-162758D01*
X410513Y-162958D01*
X410713D01*
X410913Y-163157D01*
X338444Y-265273D02*
X338844Y-264873D01*
X339244D01*
X338844Y-264473D01*
X339244Y-264073D01*
X338844D01*
X338444Y-263673D01*
X338044Y-264073D01*
X337644D01*
X338044Y-264473D01*
X337644Y-264873D01*
X338044D01*
X338444Y-265273D01*
Y-264873D02*
X338644Y-264673D01*
X338844D01*
X338644Y-264473D01*
X338844Y-264273D01*
X338644D01*
X338444Y-264073D01*
X338244Y-264273D01*
X338044D01*
X338244Y-264473D01*
X338044Y-264673D01*
X338244D01*
X338444Y-264873D01*
X456299Y-294550D02*
X456699Y-294150D01*
X457099D01*
X456699Y-293750D01*
X457099Y-293350D01*
X456699D01*
X456299Y-292950D01*
X455899Y-293350D01*
X455499D01*
X455899Y-293750D01*
X455499Y-294150D01*
X455899D01*
X456299Y-294550D01*
Y-294150D02*
X456499Y-293950D01*
X456699D01*
X456499Y-293750D01*
X456699Y-293550D01*
X456499D01*
X456299Y-293350D01*
X456099Y-293550D01*
X455899D01*
X456099Y-293750D01*
X455899Y-293950D01*
X456099D01*
X456299Y-294150D01*
X437795Y-294550D02*
X438195Y-294150D01*
X438595D01*
X438195Y-293750D01*
X438595Y-293350D01*
X438195D01*
X437795Y-292950D01*
X437395Y-293350D01*
X436995D01*
X437395Y-293750D01*
X436995Y-294150D01*
X437395D01*
X437795Y-294550D01*
Y-294150D02*
X437995Y-293950D01*
X438195D01*
X437995Y-293750D01*
X438195Y-293550D01*
X437995D01*
X437795Y-293350D01*
X437595Y-293550D01*
X437395D01*
X437595Y-293750D01*
X437395Y-293950D01*
X437595D01*
X437795Y-294150D01*
X525591Y-214235D02*
X525991Y-213835D01*
X526391D01*
X525991Y-213435D01*
X526391Y-213035D01*
X525991D01*
X525591Y-212635D01*
X525191Y-213035D01*
X524791D01*
X525191Y-213435D01*
X524791Y-213835D01*
X525191D01*
X525591Y-214235D01*
Y-213835D02*
X525791Y-213635D01*
X525991D01*
X525791Y-213435D01*
X525991Y-213235D01*
X525791D01*
X525591Y-213035D01*
X525391Y-213235D01*
X525191D01*
X525391Y-213435D01*
X525191Y-213635D01*
X525391D01*
X525591Y-213835D01*
X459319Y-163310D02*
X459719Y-162910D01*
X460119D01*
X459719Y-162510D01*
X460119Y-162110D01*
X459719D01*
X459319Y-161710D01*
X458919Y-162110D01*
X458519D01*
X458919Y-162510D01*
X458519Y-162910D01*
X458919D01*
X459319Y-163310D01*
Y-162910D02*
X459519Y-162710D01*
X459719D01*
X459519Y-162510D01*
X459719Y-162310D01*
X459519D01*
X459319Y-162110D01*
X459119Y-162310D01*
X458919D01*
X459119Y-162510D01*
X458919Y-162710D01*
X459119D01*
X459319Y-162910D01*
Y-158722D02*
X459719Y-158322D01*
X460119D01*
X459719Y-157922D01*
X460119Y-157522D01*
X459719D01*
X459319Y-157122D01*
X458919Y-157522D01*
X458519D01*
X458919Y-157922D01*
X458519Y-158322D01*
X458919D01*
X459319Y-158722D01*
Y-158322D02*
X459519Y-158122D01*
X459719D01*
X459519Y-157922D01*
X459719Y-157722D01*
X459519D01*
X459319Y-157522D01*
X459119Y-157722D01*
X458919D01*
X459119Y-157922D01*
X458919Y-158122D01*
X459119D01*
X459319Y-158322D01*
X342744Y-244547D02*
X343144Y-244147D01*
X343544D01*
X343144Y-243747D01*
X343544Y-243347D01*
X343144D01*
X342744Y-242947D01*
X342344Y-243347D01*
X341944D01*
X342344Y-243747D01*
X341944Y-244147D01*
X342344D01*
X342744Y-244547D01*
Y-244147D02*
X342944Y-243947D01*
X343144D01*
X342944Y-243747D01*
X343144Y-243547D01*
X342944D01*
X342744Y-243347D01*
X342544Y-243547D01*
X342344D01*
X342544Y-243747D01*
X342344Y-243947D01*
X342544D01*
X342744Y-244147D01*
X412598Y-311872D02*
X412998Y-311472D01*
X413398D01*
X412998Y-311072D01*
X413398Y-310672D01*
X412998D01*
X412598Y-310272D01*
X412198Y-310672D01*
X411798D01*
X412198Y-311072D01*
X411798Y-311472D01*
X412198D01*
X412598Y-311872D01*
Y-311472D02*
X412798Y-311272D01*
X412998D01*
X412798Y-311072D01*
X412998Y-310872D01*
X412798D01*
X412598Y-310672D01*
X412398Y-310872D01*
X412198D01*
X412398Y-311072D01*
X412198Y-311272D01*
X412398D01*
X412598Y-311472D01*
X531496Y-254768D02*
X531896Y-254368D01*
X532296D01*
X531896Y-253969D01*
X532296Y-253569D01*
X531896D01*
X531496Y-253169D01*
X531096Y-253569D01*
X530696D01*
X531096Y-253969D01*
X530696Y-254368D01*
X531096D01*
X531496Y-254768D01*
Y-254368D02*
X531696Y-254169D01*
X531896D01*
X531696Y-253969D01*
X531896Y-253768D01*
X531696D01*
X531496Y-253569D01*
X531296Y-253768D01*
X531096D01*
X531296Y-253969D01*
X531096Y-254169D01*
X531296D01*
X531496Y-254368D01*
X449803Y-158723D02*
X450203Y-158323D01*
X450603D01*
X450203Y-157923D01*
X450603Y-157523D01*
X450203D01*
X449803Y-157123D01*
X449403Y-157523D01*
X449003D01*
X449403Y-157923D01*
X449003Y-158323D01*
X449403D01*
X449803Y-158723D01*
Y-158323D02*
X450003Y-158123D01*
X450203D01*
X450003Y-157923D01*
X450203Y-157723D01*
X450003D01*
X449803Y-157523D01*
X449603Y-157723D01*
X449403D01*
X449603Y-157923D01*
X449403Y-158123D01*
X449603D01*
X449803Y-158323D01*
X338744Y-206273D02*
X339144Y-205873D01*
X339544D01*
X339144Y-205473D01*
X339544Y-205073D01*
X339144D01*
X338744Y-204673D01*
X338344Y-205073D01*
X337944D01*
X338344Y-205473D01*
X337944Y-205873D01*
X338344D01*
X338744Y-206273D01*
Y-205873D02*
X338944Y-205673D01*
X339144D01*
X338944Y-205473D01*
X339144Y-205273D01*
X338944D01*
X338744Y-205073D01*
X338544Y-205273D01*
X338344D01*
X338544Y-205473D01*
X338344Y-205673D01*
X338544D01*
X338744Y-205873D01*
X531496Y-204392D02*
X531896Y-203992D01*
X532296D01*
X531896Y-203592D01*
X532296Y-203192D01*
X531896D01*
X531496Y-202792D01*
X531096Y-203192D01*
X530696D01*
X531096Y-203592D01*
X530696Y-203992D01*
X531096D01*
X531496Y-204392D01*
Y-203992D02*
X531696Y-203792D01*
X531896D01*
X531696Y-203592D01*
X531896Y-203392D01*
X531696D01*
X531496Y-203192D01*
X531296Y-203392D01*
X531096D01*
X531296Y-203592D01*
X531096Y-203792D01*
X531296D01*
X531496Y-203992D01*
X401279Y-163309D02*
X401680Y-162909D01*
X402079D01*
X401680Y-162509D01*
X402079Y-162109D01*
X401680D01*
X401279Y-161709D01*
X400879Y-162109D01*
X400480D01*
X400879Y-162509D01*
X400480Y-162909D01*
X400879D01*
X401279Y-163309D01*
Y-162909D02*
X401479Y-162709D01*
X401680D01*
X401479Y-162509D01*
X401680Y-162309D01*
X401479D01*
X401279Y-162109D01*
X401080Y-162309D01*
X400879D01*
X401080Y-162509D01*
X400879Y-162709D01*
X401080D01*
X401279Y-162909D01*
X439961Y-158723D02*
X440361Y-158323D01*
X440761D01*
X440361Y-157923D01*
X440761Y-157523D01*
X440361D01*
X439961Y-157123D01*
X439561Y-157523D01*
X439161D01*
X439561Y-157923D01*
X439161Y-158323D01*
X439561D01*
X439961Y-158723D01*
Y-158323D02*
X440161Y-158123D01*
X440361D01*
X440161Y-157923D01*
X440361Y-157723D01*
X440161D01*
X439961Y-157523D01*
X439761Y-157723D01*
X439561D01*
X439761Y-157923D01*
X439561Y-158123D01*
X439761D01*
X439961Y-158323D01*
X338444Y-255573D02*
X338844Y-255173D01*
X339244D01*
X338844Y-254773D01*
X339244Y-254373D01*
X338844D01*
X338444Y-253973D01*
X338044Y-254373D01*
X337644D01*
X338044Y-254773D01*
X337644Y-255173D01*
X338044D01*
X338444Y-255573D01*
Y-255173D02*
X338644Y-254973D01*
X338844D01*
X338644Y-254773D01*
X338844Y-254573D01*
X338644D01*
X338444Y-254373D01*
X338244Y-254573D01*
X338044D01*
X338244Y-254773D01*
X338044Y-254973D01*
X338244D01*
X338444Y-255173D01*
X461417Y-294550D02*
X461817Y-294150D01*
X462217D01*
X461817Y-293750D01*
X462217Y-293350D01*
X461817D01*
X461417Y-292950D01*
X461017Y-293350D01*
X460617D01*
X461017Y-293750D01*
X460617Y-294150D01*
X461017D01*
X461417Y-294550D01*
Y-294150D02*
X461617Y-293950D01*
X461817D01*
X461617Y-293750D01*
X461817Y-293550D01*
X461617D01*
X461417Y-293350D01*
X461217Y-293550D01*
X461017D01*
X461217Y-293750D01*
X461017Y-293950D01*
X461217D01*
X461417Y-294150D01*
X525591Y-224077D02*
X525991Y-223677D01*
X526391D01*
X525991Y-223277D01*
X526391Y-222877D01*
X525991D01*
X525591Y-222477D01*
X525191Y-222877D01*
X524791D01*
X525191Y-223277D01*
X524791Y-223677D01*
X525191D01*
X525591Y-224077D01*
Y-223677D02*
X525791Y-223477D01*
X525991D01*
X525791Y-223277D01*
X525991Y-223077D01*
X525791D01*
X525591Y-222877D01*
X525391Y-223077D01*
X525191D01*
X525391Y-223277D01*
X525191Y-223477D01*
X525391D01*
X525591Y-223677D01*
X449508Y-163349D02*
X449908Y-162949D01*
X450308D01*
X449908Y-162549D01*
X450308Y-162149D01*
X449908D01*
X449508Y-161749D01*
X449108Y-162149D01*
X448708D01*
X449108Y-162549D01*
X448708Y-162949D01*
X449108D01*
X449508Y-163349D01*
Y-162949D02*
X449708Y-162749D01*
X449908D01*
X449708Y-162549D01*
X449908Y-162349D01*
X449708D01*
X449508Y-162149D01*
X449308Y-162349D01*
X449108D01*
X449308Y-162549D01*
X449108Y-162749D01*
X449308D01*
X449508Y-162949D01*
X343504Y-236036D02*
X343904Y-235636D01*
X344304D01*
X343904Y-235236D01*
X344304Y-234836D01*
X343904D01*
X343504Y-234436D01*
X343104Y-234836D01*
X342704D01*
X343104Y-235236D01*
X342704Y-235636D01*
X343104D01*
X343504Y-236036D01*
Y-235636D02*
X343704Y-235436D01*
X343904D01*
X343704Y-235236D01*
X343904Y-235036D01*
X343704D01*
X343504Y-234836D01*
X343304Y-235036D01*
X343104D01*
X343304Y-235236D01*
X343104Y-235436D01*
X343304D01*
X343504Y-235636D01*
X412205Y-294550D02*
X412605Y-294150D01*
X413005D01*
X412605Y-293750D01*
X413005Y-293350D01*
X412605D01*
X412205Y-292950D01*
X411805Y-293350D01*
X411405D01*
X411805Y-293750D01*
X411405Y-294150D01*
X411805D01*
X412205Y-294550D01*
Y-294150D02*
X412405Y-293950D01*
X412605D01*
X412405Y-293750D01*
X412605Y-293550D01*
X412405D01*
X412205Y-293350D01*
X412005Y-293550D01*
X411805D01*
X412005Y-293750D01*
X411805Y-293950D01*
X412005D01*
X412205Y-294150D01*
X639750Y-315381D02*
X640150Y-314981D01*
X640550D01*
X640150Y-314581D01*
X640550Y-314181D01*
X640150D01*
X639750Y-313781D01*
X639350Y-314181D01*
X638950D01*
X639350Y-314581D01*
X638950Y-314981D01*
X639350D01*
X639750Y-315381D01*
Y-314981D02*
X639950Y-314781D01*
X640150D01*
X639950Y-314581D01*
X640150Y-314381D01*
X639950D01*
X639750Y-314181D01*
X639550Y-314381D01*
X639350D01*
X639550Y-314581D01*
X639350Y-314781D01*
X639550D01*
X639750Y-314981D01*
X658647Y-315381D02*
X659047Y-314981D01*
X659447D01*
X659047Y-314581D01*
X659447Y-314181D01*
X659047D01*
X658647Y-313781D01*
X658247Y-314181D01*
X657847D01*
X658247Y-314581D01*
X657847Y-314981D01*
X658247D01*
X658647Y-315381D01*
Y-314981D02*
X658847Y-314781D01*
X659047D01*
X658847Y-314581D01*
X659047Y-314381D01*
X658847D01*
X658647Y-314181D01*
X658447Y-314381D01*
X658247D01*
X658447Y-314581D01*
X658247Y-314781D01*
X658447D01*
X658647Y-314981D01*
X509405Y-345938D02*
X509805Y-345538D01*
X510205D01*
X509805Y-345138D01*
X510205Y-344738D01*
X509805D01*
X509405Y-344338D01*
X509005Y-344738D01*
X508605D01*
X509005Y-345138D01*
X508605Y-345538D01*
X509005D01*
X509405Y-345938D01*
Y-345538D02*
X509605Y-345338D01*
X509805D01*
X509605Y-345138D01*
X509805Y-344938D01*
X509605D01*
X509405Y-344738D01*
X509205Y-344938D01*
X509005D01*
X509205Y-345138D01*
X509005Y-345338D01*
X509205D01*
X509405Y-345538D01*
X509011Y-330977D02*
X509411Y-330577D01*
X509811D01*
X509411Y-330177D01*
X509811Y-329777D01*
X509411D01*
X509011Y-329377D01*
X508611Y-329777D01*
X508211D01*
X508611Y-330177D01*
X508211Y-330577D01*
X508611D01*
X509011Y-330977D01*
Y-330577D02*
X509211Y-330377D01*
X509411D01*
X509211Y-330177D01*
X509411Y-329977D01*
X509211D01*
X509011Y-329777D01*
X508811Y-329977D01*
X508611D01*
X508811Y-330177D01*
X508611Y-330377D01*
X508811D01*
X509011Y-330577D01*
X56441Y-144400D02*
X56841Y-144000D01*
X57241D01*
X56841Y-143600D01*
X57241Y-143200D01*
X56841D01*
X56441Y-142800D01*
X56041Y-143200D01*
X55641D01*
X56041Y-143600D01*
X55641Y-144000D01*
X56041D01*
X56441Y-144400D01*
Y-144000D02*
X56641Y-143800D01*
X56841D01*
X56641Y-143600D01*
X56841Y-143400D01*
X56641D01*
X56441Y-143200D01*
X56241Y-143400D01*
X56041D01*
X56241Y-143600D01*
X56041Y-143800D01*
X56241D01*
X56441Y-144000D01*
Y-152400D02*
X56841Y-152000D01*
X57241D01*
X56841Y-151600D01*
X57241Y-151200D01*
X56841D01*
X56441Y-150800D01*
X56041Y-151200D01*
X55641D01*
X56041Y-151600D01*
X55641Y-152000D01*
X56041D01*
X56441Y-152400D01*
Y-152000D02*
X56641Y-151800D01*
X56841D01*
X56641Y-151600D01*
X56841Y-151400D01*
X56641D01*
X56441Y-151200D01*
X56241Y-151400D01*
X56041D01*
X56241Y-151600D01*
X56041Y-151800D01*
X56241D01*
X56441Y-152000D01*
Y-192400D02*
X56841Y-192000D01*
X57241D01*
X56841Y-191600D01*
X57241Y-191200D01*
X56841D01*
X56441Y-190800D01*
X56041Y-191200D01*
X55641D01*
X56041Y-191600D01*
X55641Y-192000D01*
X56041D01*
X56441Y-192400D01*
Y-192000D02*
X56641Y-191800D01*
X56841D01*
X56641Y-191600D01*
X56841Y-191400D01*
X56641D01*
X56441Y-191200D01*
X56241Y-191400D01*
X56041D01*
X56241Y-191600D01*
X56041Y-191800D01*
X56241D01*
X56441Y-192000D01*
Y-200400D02*
X56841Y-200000D01*
X57241D01*
X56841Y-199600D01*
X57241Y-199200D01*
X56841D01*
X56441Y-198800D01*
X56041Y-199200D01*
X55641D01*
X56041Y-199600D01*
X55641Y-200000D01*
X56041D01*
X56441Y-200400D01*
Y-200000D02*
X56641Y-199800D01*
X56841D01*
X56641Y-199600D01*
X56841Y-199400D01*
X56641D01*
X56441Y-199200D01*
X56241Y-199400D01*
X56041D01*
X56241Y-199600D01*
X56041Y-199800D01*
X56241D01*
X56441Y-200000D01*
Y-216400D02*
X56841Y-216000D01*
X57241D01*
X56841Y-215600D01*
X57241Y-215200D01*
X56841D01*
X56441Y-214800D01*
X56041Y-215200D01*
X55641D01*
X56041Y-215600D01*
X55641Y-216000D01*
X56041D01*
X56441Y-216400D01*
Y-216000D02*
X56641Y-215800D01*
X56841D01*
X56641Y-215600D01*
X56841Y-215400D01*
X56641D01*
X56441Y-215200D01*
X56241Y-215400D01*
X56041D01*
X56241Y-215600D01*
X56041Y-215800D01*
X56241D01*
X56441Y-216000D01*
Y-224400D02*
X56841Y-224000D01*
X57241D01*
X56841Y-223600D01*
X57241Y-223200D01*
X56841D01*
X56441Y-222800D01*
X56041Y-223200D01*
X55641D01*
X56041Y-223600D01*
X55641Y-224000D01*
X56041D01*
X56441Y-224400D01*
Y-224000D02*
X56641Y-223800D01*
X56841D01*
X56641Y-223600D01*
X56841Y-223400D01*
X56641D01*
X56441Y-223200D01*
X56241Y-223400D01*
X56041D01*
X56241Y-223600D01*
X56041Y-223800D01*
X56241D01*
X56441Y-224000D01*
Y-232400D02*
X56841Y-232000D01*
X57241D01*
X56841Y-231600D01*
X57241Y-231200D01*
X56841D01*
X56441Y-230800D01*
X56041Y-231200D01*
X55641D01*
X56041Y-231600D01*
X55641Y-232000D01*
X56041D01*
X56441Y-232400D01*
Y-232000D02*
X56641Y-231800D01*
X56841D01*
X56641Y-231600D01*
X56841Y-231400D01*
X56641D01*
X56441Y-231200D01*
X56241Y-231400D01*
X56041D01*
X56241Y-231600D01*
X56041Y-231800D01*
X56241D01*
X56441Y-232000D01*
Y-248400D02*
X56841Y-248000D01*
X57241D01*
X56841Y-247600D01*
X57241Y-247200D01*
X56841D01*
X56441Y-246800D01*
X56041Y-247200D01*
X55641D01*
X56041Y-247600D01*
X55641Y-248000D01*
X56041D01*
X56441Y-248400D01*
Y-248000D02*
X56641Y-247800D01*
X56841D01*
X56641Y-247600D01*
X56841Y-247400D01*
X56641D01*
X56441Y-247200D01*
X56241Y-247400D01*
X56041D01*
X56241Y-247600D01*
X56041Y-247800D01*
X56241D01*
X56441Y-248000D01*
Y-256400D02*
X56841Y-256000D01*
X57241D01*
X56841Y-255600D01*
X57241Y-255200D01*
X56841D01*
X56441Y-254800D01*
X56041Y-255200D01*
X55641D01*
X56041Y-255600D01*
X55641Y-256000D01*
X56041D01*
X56441Y-256400D01*
Y-256000D02*
X56641Y-255800D01*
X56841D01*
X56641Y-255600D01*
X56841Y-255400D01*
X56641D01*
X56441Y-255200D01*
X56241Y-255400D01*
X56041D01*
X56241Y-255600D01*
X56041Y-255800D01*
X56241D01*
X56441Y-256000D01*
Y-272400D02*
X56841Y-272000D01*
X57241D01*
X56841Y-271600D01*
X57241Y-271200D01*
X56841D01*
X56441Y-270800D01*
X56041Y-271200D01*
X55641D01*
X56041Y-271600D01*
X55641Y-272000D01*
X56041D01*
X56441Y-272400D01*
Y-272000D02*
X56641Y-271800D01*
X56841D01*
X56641Y-271600D01*
X56841Y-271400D01*
X56641D01*
X56441Y-271200D01*
X56241Y-271400D01*
X56041D01*
X56241Y-271600D01*
X56041Y-271800D01*
X56241D01*
X56441Y-272000D01*
Y-280400D02*
X56841Y-280000D01*
X57241D01*
X56841Y-279600D01*
X57241Y-279200D01*
X56841D01*
X56441Y-278800D01*
X56041Y-279200D01*
X55641D01*
X56041Y-279600D01*
X55641Y-280000D01*
X56041D01*
X56441Y-280400D01*
Y-280000D02*
X56641Y-279800D01*
X56841D01*
X56641Y-279600D01*
X56841Y-279400D01*
X56641D01*
X56441Y-279200D01*
X56241Y-279400D01*
X56041D01*
X56241Y-279600D01*
X56041Y-279800D01*
X56241D01*
X56441Y-280000D01*
Y-288400D02*
X56841Y-288000D01*
X57241D01*
X56841Y-287600D01*
X57241Y-287200D01*
X56841D01*
X56441Y-286800D01*
X56041Y-287200D01*
X55641D01*
X56041Y-287600D01*
X55641Y-288000D01*
X56041D01*
X56441Y-288400D01*
Y-288000D02*
X56641Y-287800D01*
X56841D01*
X56641Y-287600D01*
X56841Y-287400D01*
X56641D01*
X56441Y-287200D01*
X56241Y-287400D01*
X56041D01*
X56241Y-287600D01*
X56041Y-287800D01*
X56241D01*
X56441Y-288000D01*
Y-304400D02*
X56841Y-304000D01*
X57241D01*
X56841Y-303600D01*
X57241Y-303200D01*
X56841D01*
X56441Y-302800D01*
X56041Y-303200D01*
X55641D01*
X56041Y-303600D01*
X55641Y-304000D01*
X56041D01*
X56441Y-304400D01*
Y-304000D02*
X56641Y-303800D01*
X56841D01*
X56641Y-303600D01*
X56841Y-303400D01*
X56641D01*
X56441Y-303200D01*
X56241Y-303400D01*
X56041D01*
X56241Y-303600D01*
X56041Y-303800D01*
X56241D01*
X56441Y-304000D01*
Y-312400D02*
X56841Y-312000D01*
X57241D01*
X56841Y-311600D01*
X57241Y-311200D01*
X56841D01*
X56441Y-310800D01*
X56041Y-311200D01*
X55641D01*
X56041Y-311600D01*
X55641Y-312000D01*
X56041D01*
X56441Y-312400D01*
Y-312000D02*
X56641Y-311800D01*
X56841D01*
X56641Y-311600D01*
X56841Y-311400D01*
X56641D01*
X56441Y-311200D01*
X56241Y-311400D01*
X56041D01*
X56241Y-311600D01*
X56041Y-311800D01*
X56241D01*
X56441Y-312000D01*
Y-328400D02*
X56841Y-328000D01*
X57241D01*
X56841Y-327600D01*
X57241Y-327200D01*
X56841D01*
X56441Y-326800D01*
X56041Y-327200D01*
X55641D01*
X56041Y-327600D01*
X55641Y-328000D01*
X56041D01*
X56441Y-328400D01*
Y-328000D02*
X56641Y-327800D01*
X56841D01*
X56641Y-327600D01*
X56841Y-327400D01*
X56641D01*
X56441Y-327200D01*
X56241Y-327400D01*
X56041D01*
X56241Y-327600D01*
X56041Y-327800D01*
X56241D01*
X56441Y-328000D01*
Y-336400D02*
X56841Y-336000D01*
X57241D01*
X56841Y-335600D01*
X57241Y-335200D01*
X56841D01*
X56441Y-334800D01*
X56041Y-335200D01*
X55641D01*
X56041Y-335600D01*
X55641Y-336000D01*
X56041D01*
X56441Y-336400D01*
Y-336000D02*
X56641Y-335800D01*
X56841D01*
X56641Y-335600D01*
X56841Y-335400D01*
X56641D01*
X56441Y-335200D01*
X56241Y-335400D01*
X56041D01*
X56241Y-335600D01*
X56041Y-335800D01*
X56241D01*
X56441Y-336000D01*
Y-344400D02*
X56841Y-344000D01*
X57241D01*
X56841Y-343600D01*
X57241Y-343200D01*
X56841D01*
X56441Y-342800D01*
X56041Y-343200D01*
X55641D01*
X56041Y-343600D01*
X55641Y-344000D01*
X56041D01*
X56441Y-344400D01*
Y-344000D02*
X56641Y-343800D01*
X56841D01*
X56641Y-343600D01*
X56841Y-343400D01*
X56641D01*
X56441Y-343200D01*
X56241Y-343400D01*
X56041D01*
X56241Y-343600D01*
X56041Y-343800D01*
X56241D01*
X56441Y-344000D01*
Y-352400D02*
X56841Y-352000D01*
X57241D01*
X56841Y-351600D01*
X57241Y-351200D01*
X56841D01*
X56441Y-350800D01*
X56041Y-351200D01*
X55641D01*
X56041Y-351600D01*
X55641Y-352000D01*
X56041D01*
X56441Y-352400D01*
Y-352000D02*
X56641Y-351800D01*
X56841D01*
X56641Y-351600D01*
X56841Y-351400D01*
X56641D01*
X56441Y-351200D01*
X56241Y-351400D01*
X56041D01*
X56241Y-351600D01*
X56041Y-351800D01*
X56241D01*
X56441Y-352000D01*
X54441Y-140400D02*
X54841Y-140000D01*
X55241D01*
X54841Y-139600D01*
X55241Y-139200D01*
X54841D01*
X54441Y-138800D01*
X54041Y-139200D01*
X53641D01*
X54041Y-139600D01*
X53641Y-140000D01*
X54041D01*
X54441Y-140400D01*
Y-140000D02*
X54641Y-139800D01*
X54841D01*
X54641Y-139600D01*
X54841Y-139400D01*
X54641D01*
X54441Y-139200D01*
X54241Y-139400D01*
X54041D01*
X54241Y-139600D01*
X54041Y-139800D01*
X54241D01*
X54441Y-140000D01*
X52441Y-144400D02*
X52841Y-144000D01*
X53241D01*
X52841Y-143600D01*
X53241Y-143200D01*
X52841D01*
X52441Y-142800D01*
X52041Y-143200D01*
X51641D01*
X52041Y-143600D01*
X51641Y-144000D01*
X52041D01*
X52441Y-144400D01*
Y-144000D02*
X52641Y-143800D01*
X52841D01*
X52641Y-143600D01*
X52841Y-143400D01*
X52641D01*
X52441Y-143200D01*
X52241Y-143400D01*
X52041D01*
X52241Y-143600D01*
X52041Y-143800D01*
X52241D01*
X52441Y-144000D01*
X54441Y-148400D02*
X54841Y-148000D01*
X55241D01*
X54841Y-147600D01*
X55241Y-147200D01*
X54841D01*
X54441Y-146800D01*
X54041Y-147200D01*
X53641D01*
X54041Y-147600D01*
X53641Y-148000D01*
X54041D01*
X54441Y-148400D01*
Y-148000D02*
X54641Y-147800D01*
X54841D01*
X54641Y-147600D01*
X54841Y-147400D01*
X54641D01*
X54441Y-147200D01*
X54241Y-147400D01*
X54041D01*
X54241Y-147600D01*
X54041Y-147800D01*
X54241D01*
X54441Y-148000D01*
X52441Y-152400D02*
X52841Y-152000D01*
X53241D01*
X52841Y-151600D01*
X53241Y-151200D01*
X52841D01*
X52441Y-150800D01*
X52041Y-151200D01*
X51641D01*
X52041Y-151600D01*
X51641Y-152000D01*
X52041D01*
X52441Y-152400D01*
Y-152000D02*
X52641Y-151800D01*
X52841D01*
X52641Y-151600D01*
X52841Y-151400D01*
X52641D01*
X52441Y-151200D01*
X52241Y-151400D01*
X52041D01*
X52241Y-151600D01*
X52041Y-151800D01*
X52241D01*
X52441Y-152000D01*
Y-192400D02*
X52841Y-192000D01*
X53241D01*
X52841Y-191600D01*
X53241Y-191200D01*
X52841D01*
X52441Y-190800D01*
X52041Y-191200D01*
X51641D01*
X52041Y-191600D01*
X51641Y-192000D01*
X52041D01*
X52441Y-192400D01*
Y-192000D02*
X52641Y-191800D01*
X52841D01*
X52641Y-191600D01*
X52841Y-191400D01*
X52641D01*
X52441Y-191200D01*
X52241Y-191400D01*
X52041D01*
X52241Y-191600D01*
X52041Y-191800D01*
X52241D01*
X52441Y-192000D01*
X54441Y-196400D02*
X54841Y-196000D01*
X55241D01*
X54841Y-195600D01*
X55241Y-195200D01*
X54841D01*
X54441Y-194800D01*
X54041Y-195200D01*
X53641D01*
X54041Y-195600D01*
X53641Y-196000D01*
X54041D01*
X54441Y-196400D01*
Y-196000D02*
X54641Y-195800D01*
X54841D01*
X54641Y-195600D01*
X54841Y-195400D01*
X54641D01*
X54441Y-195200D01*
X54241Y-195400D01*
X54041D01*
X54241Y-195600D01*
X54041Y-195800D01*
X54241D01*
X54441Y-196000D01*
X52441Y-200400D02*
X52841Y-200000D01*
X53241D01*
X52841Y-199600D01*
X53241Y-199200D01*
X52841D01*
X52441Y-198800D01*
X52041Y-199200D01*
X51641D01*
X52041Y-199600D01*
X51641Y-200000D01*
X52041D01*
X52441Y-200400D01*
Y-200000D02*
X52641Y-199800D01*
X52841D01*
X52641Y-199600D01*
X52841Y-199400D01*
X52641D01*
X52441Y-199200D01*
X52241Y-199400D01*
X52041D01*
X52241Y-199600D01*
X52041Y-199800D01*
X52241D01*
X52441Y-200000D01*
X54441Y-204400D02*
X54841Y-204000D01*
X55241D01*
X54841Y-203600D01*
X55241Y-203200D01*
X54841D01*
X54441Y-202800D01*
X54041Y-203200D01*
X53641D01*
X54041Y-203600D01*
X53641Y-204000D01*
X54041D01*
X54441Y-204400D01*
Y-204000D02*
X54641Y-203800D01*
X54841D01*
X54641Y-203600D01*
X54841Y-203400D01*
X54641D01*
X54441Y-203200D01*
X54241Y-203400D01*
X54041D01*
X54241Y-203600D01*
X54041Y-203800D01*
X54241D01*
X54441Y-204000D01*
X52441Y-216400D02*
X52841Y-216000D01*
X53241D01*
X52841Y-215600D01*
X53241Y-215200D01*
X52841D01*
X52441Y-214800D01*
X52041Y-215200D01*
X51641D01*
X52041Y-215600D01*
X51641Y-216000D01*
X52041D01*
X52441Y-216400D01*
Y-216000D02*
X52641Y-215800D01*
X52841D01*
X52641Y-215600D01*
X52841Y-215400D01*
X52641D01*
X52441Y-215200D01*
X52241Y-215400D01*
X52041D01*
X52241Y-215600D01*
X52041Y-215800D01*
X52241D01*
X52441Y-216000D01*
X54441Y-220400D02*
X54841Y-220000D01*
X55241D01*
X54841Y-219600D01*
X55241Y-219200D01*
X54841D01*
X54441Y-218800D01*
X54041Y-219200D01*
X53641D01*
X54041Y-219600D01*
X53641Y-220000D01*
X54041D01*
X54441Y-220400D01*
Y-220000D02*
X54641Y-219800D01*
X54841D01*
X54641Y-219600D01*
X54841Y-219400D01*
X54641D01*
X54441Y-219200D01*
X54241Y-219400D01*
X54041D01*
X54241Y-219600D01*
X54041Y-219800D01*
X54241D01*
X54441Y-220000D01*
X52441Y-224400D02*
X52841Y-224000D01*
X53241D01*
X52841Y-223600D01*
X53241Y-223200D01*
X52841D01*
X52441Y-222800D01*
X52041Y-223200D01*
X51641D01*
X52041Y-223600D01*
X51641Y-224000D01*
X52041D01*
X52441Y-224400D01*
Y-224000D02*
X52641Y-223800D01*
X52841D01*
X52641Y-223600D01*
X52841Y-223400D01*
X52641D01*
X52441Y-223200D01*
X52241Y-223400D01*
X52041D01*
X52241Y-223600D01*
X52041Y-223800D01*
X52241D01*
X52441Y-224000D01*
X54441Y-228400D02*
X54841Y-228000D01*
X55241D01*
X54841Y-227600D01*
X55241Y-227200D01*
X54841D01*
X54441Y-226800D01*
X54041Y-227200D01*
X53641D01*
X54041Y-227600D01*
X53641Y-228000D01*
X54041D01*
X54441Y-228400D01*
Y-228000D02*
X54641Y-227800D01*
X54841D01*
X54641Y-227600D01*
X54841Y-227400D01*
X54641D01*
X54441Y-227200D01*
X54241Y-227400D01*
X54041D01*
X54241Y-227600D01*
X54041Y-227800D01*
X54241D01*
X54441Y-228000D01*
X52441Y-232400D02*
X52841Y-232000D01*
X53241D01*
X52841Y-231600D01*
X53241Y-231200D01*
X52841D01*
X52441Y-230800D01*
X52041Y-231200D01*
X51641D01*
X52041Y-231600D01*
X51641Y-232000D01*
X52041D01*
X52441Y-232400D01*
Y-232000D02*
X52641Y-231800D01*
X52841D01*
X52641Y-231600D01*
X52841Y-231400D01*
X52641D01*
X52441Y-231200D01*
X52241Y-231400D01*
X52041D01*
X52241Y-231600D01*
X52041Y-231800D01*
X52241D01*
X52441Y-232000D01*
X54441Y-236400D02*
X54841Y-236000D01*
X55241D01*
X54841Y-235600D01*
X55241Y-235200D01*
X54841D01*
X54441Y-234800D01*
X54041Y-235200D01*
X53641D01*
X54041Y-235600D01*
X53641Y-236000D01*
X54041D01*
X54441Y-236400D01*
Y-236000D02*
X54641Y-235800D01*
X54841D01*
X54641Y-235600D01*
X54841Y-235400D01*
X54641D01*
X54441Y-235200D01*
X54241Y-235400D01*
X54041D01*
X54241Y-235600D01*
X54041Y-235800D01*
X54241D01*
X54441Y-236000D01*
Y-244400D02*
X54841Y-244000D01*
X55241D01*
X54841Y-243600D01*
X55241Y-243200D01*
X54841D01*
X54441Y-242800D01*
X54041Y-243200D01*
X53641D01*
X54041Y-243600D01*
X53641Y-244000D01*
X54041D01*
X54441Y-244400D01*
Y-244000D02*
X54641Y-243800D01*
X54841D01*
X54641Y-243600D01*
X54841Y-243400D01*
X54641D01*
X54441Y-243200D01*
X54241Y-243400D01*
X54041D01*
X54241Y-243600D01*
X54041Y-243800D01*
X54241D01*
X54441Y-244000D01*
X52441Y-248400D02*
X52841Y-248000D01*
X53241D01*
X52841Y-247600D01*
X53241Y-247200D01*
X52841D01*
X52441Y-246800D01*
X52041Y-247200D01*
X51641D01*
X52041Y-247600D01*
X51641Y-248000D01*
X52041D01*
X52441Y-248400D01*
Y-248000D02*
X52641Y-247800D01*
X52841D01*
X52641Y-247600D01*
X52841Y-247400D01*
X52641D01*
X52441Y-247200D01*
X52241Y-247400D01*
X52041D01*
X52241Y-247600D01*
X52041Y-247800D01*
X52241D01*
X52441Y-248000D01*
X54441Y-252400D02*
X54841Y-252000D01*
X55241D01*
X54841Y-251600D01*
X55241Y-251200D01*
X54841D01*
X54441Y-250800D01*
X54041Y-251200D01*
X53641D01*
X54041Y-251600D01*
X53641Y-252000D01*
X54041D01*
X54441Y-252400D01*
Y-252000D02*
X54641Y-251800D01*
X54841D01*
X54641Y-251600D01*
X54841Y-251400D01*
X54641D01*
X54441Y-251200D01*
X54241Y-251400D01*
X54041D01*
X54241Y-251600D01*
X54041Y-251800D01*
X54241D01*
X54441Y-252000D01*
X52441Y-256400D02*
X52841Y-256000D01*
X53241D01*
X52841Y-255600D01*
X53241Y-255200D01*
X52841D01*
X52441Y-254800D01*
X52041Y-255200D01*
X51641D01*
X52041Y-255600D01*
X51641Y-256000D01*
X52041D01*
X52441Y-256400D01*
Y-256000D02*
X52641Y-255800D01*
X52841D01*
X52641Y-255600D01*
X52841Y-255400D01*
X52641D01*
X52441Y-255200D01*
X52241Y-255400D01*
X52041D01*
X52241Y-255600D01*
X52041Y-255800D01*
X52241D01*
X52441Y-256000D01*
X54441Y-268400D02*
X54841Y-268000D01*
X55241D01*
X54841Y-267600D01*
X55241Y-267200D01*
X54841D01*
X54441Y-266800D01*
X54041Y-267200D01*
X53641D01*
X54041Y-267600D01*
X53641Y-268000D01*
X54041D01*
X54441Y-268400D01*
Y-268000D02*
X54641Y-267800D01*
X54841D01*
X54641Y-267600D01*
X54841Y-267400D01*
X54641D01*
X54441Y-267200D01*
X54241Y-267400D01*
X54041D01*
X54241Y-267600D01*
X54041Y-267800D01*
X54241D01*
X54441Y-268000D01*
X52441Y-272400D02*
X52841Y-272000D01*
X53241D01*
X52841Y-271600D01*
X53241Y-271200D01*
X52841D01*
X52441Y-270800D01*
X52041Y-271200D01*
X51641D01*
X52041Y-271600D01*
X51641Y-272000D01*
X52041D01*
X52441Y-272400D01*
Y-272000D02*
X52641Y-271800D01*
X52841D01*
X52641Y-271600D01*
X52841Y-271400D01*
X52641D01*
X52441Y-271200D01*
X52241Y-271400D01*
X52041D01*
X52241Y-271600D01*
X52041Y-271800D01*
X52241D01*
X52441Y-272000D01*
X54441Y-276400D02*
X54841Y-276000D01*
X55241D01*
X54841Y-275600D01*
X55241Y-275200D01*
X54841D01*
X54441Y-274800D01*
X54041Y-275200D01*
X53641D01*
X54041Y-275600D01*
X53641Y-276000D01*
X54041D01*
X54441Y-276400D01*
Y-276000D02*
X54641Y-275800D01*
X54841D01*
X54641Y-275600D01*
X54841Y-275400D01*
X54641D01*
X54441Y-275200D01*
X54241Y-275400D01*
X54041D01*
X54241Y-275600D01*
X54041Y-275800D01*
X54241D01*
X54441Y-276000D01*
X52441Y-280400D02*
X52841Y-280000D01*
X53241D01*
X52841Y-279600D01*
X53241Y-279200D01*
X52841D01*
X52441Y-278800D01*
X52041Y-279200D01*
X51641D01*
X52041Y-279600D01*
X51641Y-280000D01*
X52041D01*
X52441Y-280400D01*
Y-280000D02*
X52641Y-279800D01*
X52841D01*
X52641Y-279600D01*
X52841Y-279400D01*
X52641D01*
X52441Y-279200D01*
X52241Y-279400D01*
X52041D01*
X52241Y-279600D01*
X52041Y-279800D01*
X52241D01*
X52441Y-280000D01*
Y-288400D02*
X52841Y-288000D01*
X53241D01*
X52841Y-287600D01*
X53241Y-287200D01*
X52841D01*
X52441Y-286800D01*
X52041Y-287200D01*
X51641D01*
X52041Y-287600D01*
X51641Y-288000D01*
X52041D01*
X52441Y-288400D01*
Y-288000D02*
X52641Y-287800D01*
X52841D01*
X52641Y-287600D01*
X52841Y-287400D01*
X52641D01*
X52441Y-287200D01*
X52241Y-287400D01*
X52041D01*
X52241Y-287600D01*
X52041Y-287800D01*
X52241D01*
X52441Y-288000D01*
X54441Y-292400D02*
X54841Y-292000D01*
X55241D01*
X54841Y-291600D01*
X55241Y-291200D01*
X54841D01*
X54441Y-290800D01*
X54041Y-291200D01*
X53641D01*
X54041Y-291600D01*
X53641Y-292000D01*
X54041D01*
X54441Y-292400D01*
Y-292000D02*
X54641Y-291800D01*
X54841D01*
X54641Y-291600D01*
X54841Y-291400D01*
X54641D01*
X54441Y-291200D01*
X54241Y-291400D01*
X54041D01*
X54241Y-291600D01*
X54041Y-291800D01*
X54241D01*
X54441Y-292000D01*
Y-300400D02*
X54841Y-300000D01*
X55241D01*
X54841Y-299600D01*
X55241Y-299200D01*
X54841D01*
X54441Y-298800D01*
X54041Y-299200D01*
X53641D01*
X54041Y-299600D01*
X53641Y-300000D01*
X54041D01*
X54441Y-300400D01*
Y-300000D02*
X54641Y-299800D01*
X54841D01*
X54641Y-299600D01*
X54841Y-299400D01*
X54641D01*
X54441Y-299200D01*
X54241Y-299400D01*
X54041D01*
X54241Y-299600D01*
X54041Y-299800D01*
X54241D01*
X54441Y-300000D01*
X52441Y-304400D02*
X52841Y-304000D01*
X53241D01*
X52841Y-303600D01*
X53241Y-303200D01*
X52841D01*
X52441Y-302800D01*
X52041Y-303200D01*
X51641D01*
X52041Y-303600D01*
X51641Y-304000D01*
X52041D01*
X52441Y-304400D01*
Y-304000D02*
X52641Y-303800D01*
X52841D01*
X52641Y-303600D01*
X52841Y-303400D01*
X52641D01*
X52441Y-303200D01*
X52241Y-303400D01*
X52041D01*
X52241Y-303600D01*
X52041Y-303800D01*
X52241D01*
X52441Y-304000D01*
X54441Y-308400D02*
X54841Y-308000D01*
X55241D01*
X54841Y-307600D01*
X55241Y-307200D01*
X54841D01*
X54441Y-306800D01*
X54041Y-307200D01*
X53641D01*
X54041Y-307600D01*
X53641Y-308000D01*
X54041D01*
X54441Y-308400D01*
Y-308000D02*
X54641Y-307800D01*
X54841D01*
X54641Y-307600D01*
X54841Y-307400D01*
X54641D01*
X54441Y-307200D01*
X54241Y-307400D01*
X54041D01*
X54241Y-307600D01*
X54041Y-307800D01*
X54241D01*
X54441Y-308000D01*
X52441Y-312400D02*
X52841Y-312000D01*
X53241D01*
X52841Y-311600D01*
X53241Y-311200D01*
X52841D01*
X52441Y-310800D01*
X52041Y-311200D01*
X51641D01*
X52041Y-311600D01*
X51641Y-312000D01*
X52041D01*
X52441Y-312400D01*
Y-312000D02*
X52641Y-311800D01*
X52841D01*
X52641Y-311600D01*
X52841Y-311400D01*
X52641D01*
X52441Y-311200D01*
X52241Y-311400D01*
X52041D01*
X52241Y-311600D01*
X52041Y-311800D01*
X52241D01*
X52441Y-312000D01*
X54441Y-324400D02*
X54841Y-324000D01*
X55241D01*
X54841Y-323600D01*
X55241Y-323200D01*
X54841D01*
X54441Y-322800D01*
X54041Y-323200D01*
X53641D01*
X54041Y-323600D01*
X53641Y-324000D01*
X54041D01*
X54441Y-324400D01*
Y-324000D02*
X54641Y-323800D01*
X54841D01*
X54641Y-323600D01*
X54841Y-323400D01*
X54641D01*
X54441Y-323200D01*
X54241Y-323400D01*
X54041D01*
X54241Y-323600D01*
X54041Y-323800D01*
X54241D01*
X54441Y-324000D01*
X52441Y-328400D02*
X52841Y-328000D01*
X53241D01*
X52841Y-327600D01*
X53241Y-327200D01*
X52841D01*
X52441Y-326800D01*
X52041Y-327200D01*
X51641D01*
X52041Y-327600D01*
X51641Y-328000D01*
X52041D01*
X52441Y-328400D01*
Y-328000D02*
X52641Y-327800D01*
X52841D01*
X52641Y-327600D01*
X52841Y-327400D01*
X52641D01*
X52441Y-327200D01*
X52241Y-327400D01*
X52041D01*
X52241Y-327600D01*
X52041Y-327800D01*
X52241D01*
X52441Y-328000D01*
X54441Y-332400D02*
X54841Y-332000D01*
X55241D01*
X54841Y-331600D01*
X55241Y-331200D01*
X54841D01*
X54441Y-330800D01*
X54041Y-331200D01*
X53641D01*
X54041Y-331600D01*
X53641Y-332000D01*
X54041D01*
X54441Y-332400D01*
Y-332000D02*
X54641Y-331800D01*
X54841D01*
X54641Y-331600D01*
X54841Y-331400D01*
X54641D01*
X54441Y-331200D01*
X54241Y-331400D01*
X54041D01*
X54241Y-331600D01*
X54041Y-331800D01*
X54241D01*
X54441Y-332000D01*
X52441Y-336400D02*
X52841Y-336000D01*
X53241D01*
X52841Y-335600D01*
X53241Y-335200D01*
X52841D01*
X52441Y-334800D01*
X52041Y-335200D01*
X51641D01*
X52041Y-335600D01*
X51641Y-336000D01*
X52041D01*
X52441Y-336400D01*
Y-336000D02*
X52641Y-335800D01*
X52841D01*
X52641Y-335600D01*
X52841Y-335400D01*
X52641D01*
X52441Y-335200D01*
X52241Y-335400D01*
X52041D01*
X52241Y-335600D01*
X52041Y-335800D01*
X52241D01*
X52441Y-336000D01*
X54441Y-340400D02*
X54841Y-340000D01*
X55241D01*
X54841Y-339600D01*
X55241Y-339200D01*
X54841D01*
X54441Y-338800D01*
X54041Y-339200D01*
X53641D01*
X54041Y-339600D01*
X53641Y-340000D01*
X54041D01*
X54441Y-340400D01*
Y-340000D02*
X54641Y-339800D01*
X54841D01*
X54641Y-339600D01*
X54841Y-339400D01*
X54641D01*
X54441Y-339200D01*
X54241Y-339400D01*
X54041D01*
X54241Y-339600D01*
X54041Y-339800D01*
X54241D01*
X54441Y-340000D01*
X52441Y-344400D02*
X52841Y-344000D01*
X53241D01*
X52841Y-343600D01*
X53241Y-343200D01*
X52841D01*
X52441Y-342800D01*
X52041Y-343200D01*
X51641D01*
X52041Y-343600D01*
X51641Y-344000D01*
X52041D01*
X52441Y-344400D01*
Y-344000D02*
X52641Y-343800D01*
X52841D01*
X52641Y-343600D01*
X52841Y-343400D01*
X52641D01*
X52441Y-343200D01*
X52241Y-343400D01*
X52041D01*
X52241Y-343600D01*
X52041Y-343800D01*
X52241D01*
X52441Y-344000D01*
Y-352400D02*
X52841Y-352000D01*
X53241D01*
X52841Y-351600D01*
X53241Y-351200D01*
X52841D01*
X52441Y-350800D01*
X52041Y-351200D01*
X51641D01*
X52041Y-351600D01*
X51641Y-352000D01*
X52041D01*
X52441Y-352400D01*
Y-352000D02*
X52641Y-351800D01*
X52841D01*
X52641Y-351600D01*
X52841Y-351400D01*
X52641D01*
X52441Y-351200D01*
X52241Y-351400D01*
X52041D01*
X52241Y-351600D01*
X52041Y-351800D01*
X52241D01*
X52441Y-352000D01*
X50441Y-140400D02*
X50841Y-140000D01*
X51241D01*
X50841Y-139600D01*
X51241Y-139200D01*
X50841D01*
X50441Y-138800D01*
X50041Y-139200D01*
X49641D01*
X50041Y-139600D01*
X49641Y-140000D01*
X50041D01*
X50441Y-140400D01*
Y-140000D02*
X50641Y-139800D01*
X50841D01*
X50641Y-139600D01*
X50841Y-139400D01*
X50641D01*
X50441Y-139200D01*
X50241Y-139400D01*
X50041D01*
X50241Y-139600D01*
X50041Y-139800D01*
X50241D01*
X50441Y-140000D01*
X48441Y-144400D02*
X48841Y-144000D01*
X49241D01*
X48841Y-143600D01*
X49241Y-143200D01*
X48841D01*
X48441Y-142800D01*
X48041Y-143200D01*
X47641D01*
X48041Y-143600D01*
X47641Y-144000D01*
X48041D01*
X48441Y-144400D01*
Y-144000D02*
X48641Y-143800D01*
X48841D01*
X48641Y-143600D01*
X48841Y-143400D01*
X48641D01*
X48441Y-143200D01*
X48241Y-143400D01*
X48041D01*
X48241Y-143600D01*
X48041Y-143800D01*
X48241D01*
X48441Y-144000D01*
X50441Y-196400D02*
X50841Y-196000D01*
X51241D01*
X50841Y-195600D01*
X51241Y-195200D01*
X50841D01*
X50441Y-194800D01*
X50041Y-195200D01*
X49641D01*
X50041Y-195600D01*
X49641Y-196000D01*
X50041D01*
X50441Y-196400D01*
Y-196000D02*
X50641Y-195800D01*
X50841D01*
X50641Y-195600D01*
X50841Y-195400D01*
X50641D01*
X50441Y-195200D01*
X50241Y-195400D01*
X50041D01*
X50241Y-195600D01*
X50041Y-195800D01*
X50241D01*
X50441Y-196000D01*
X48441Y-200400D02*
X48841Y-200000D01*
X49241D01*
X48841Y-199600D01*
X49241Y-199200D01*
X48841D01*
X48441Y-198800D01*
X48041Y-199200D01*
X47641D01*
X48041Y-199600D01*
X47641Y-200000D01*
X48041D01*
X48441Y-200400D01*
Y-200000D02*
X48641Y-199800D01*
X48841D01*
X48641Y-199600D01*
X48841Y-199400D01*
X48641D01*
X48441Y-199200D01*
X48241Y-199400D01*
X48041D01*
X48241Y-199600D01*
X48041Y-199800D01*
X48241D01*
X48441Y-200000D01*
Y-224400D02*
X48841Y-224000D01*
X49241D01*
X48841Y-223600D01*
X49241Y-223200D01*
X48841D01*
X48441Y-222800D01*
X48041Y-223200D01*
X47641D01*
X48041Y-223600D01*
X47641Y-224000D01*
X48041D01*
X48441Y-224400D01*
Y-224000D02*
X48641Y-223800D01*
X48841D01*
X48641Y-223600D01*
X48841Y-223400D01*
X48641D01*
X48441Y-223200D01*
X48241Y-223400D01*
X48041D01*
X48241Y-223600D01*
X48041Y-223800D01*
X48241D01*
X48441Y-224000D01*
X50441Y-228400D02*
X50841Y-228000D01*
X51241D01*
X50841Y-227600D01*
X51241Y-227200D01*
X50841D01*
X50441Y-226800D01*
X50041Y-227200D01*
X49641D01*
X50041Y-227600D01*
X49641Y-228000D01*
X50041D01*
X50441Y-228400D01*
Y-228000D02*
X50641Y-227800D01*
X50841D01*
X50641Y-227600D01*
X50841Y-227400D01*
X50641D01*
X50441Y-227200D01*
X50241Y-227400D01*
X50041D01*
X50241Y-227600D01*
X50041Y-227800D01*
X50241D01*
X50441Y-228000D01*
X48441Y-232400D02*
X48841Y-232000D01*
X49241D01*
X48841Y-231600D01*
X49241Y-231200D01*
X48841D01*
X48441Y-230800D01*
X48041Y-231200D01*
X47641D01*
X48041Y-231600D01*
X47641Y-232000D01*
X48041D01*
X48441Y-232400D01*
Y-232000D02*
X48641Y-231800D01*
X48841D01*
X48641Y-231600D01*
X48841Y-231400D01*
X48641D01*
X48441Y-231200D01*
X48241Y-231400D01*
X48041D01*
X48241Y-231600D01*
X48041Y-231800D01*
X48241D01*
X48441Y-232000D01*
X50441Y-236400D02*
X50841Y-236000D01*
X51241D01*
X50841Y-235600D01*
X51241Y-235200D01*
X50841D01*
X50441Y-234800D01*
X50041Y-235200D01*
X49641D01*
X50041Y-235600D01*
X49641Y-236000D01*
X50041D01*
X50441Y-236400D01*
Y-236000D02*
X50641Y-235800D01*
X50841D01*
X50641Y-235600D01*
X50841Y-235400D01*
X50641D01*
X50441Y-235200D01*
X50241Y-235400D01*
X50041D01*
X50241Y-235600D01*
X50041Y-235800D01*
X50241D01*
X50441Y-236000D01*
Y-244400D02*
X50841Y-244000D01*
X51241D01*
X50841Y-243600D01*
X51241Y-243200D01*
X50841D01*
X50441Y-242800D01*
X50041Y-243200D01*
X49641D01*
X50041Y-243600D01*
X49641Y-244000D01*
X50041D01*
X50441Y-244400D01*
Y-244000D02*
X50641Y-243800D01*
X50841D01*
X50641Y-243600D01*
X50841Y-243400D01*
X50641D01*
X50441Y-243200D01*
X50241Y-243400D01*
X50041D01*
X50241Y-243600D01*
X50041Y-243800D01*
X50241D01*
X50441Y-244000D01*
X48441Y-248400D02*
X48841Y-248000D01*
X49241D01*
X48841Y-247600D01*
X49241Y-247200D01*
X48841D01*
X48441Y-246800D01*
X48041Y-247200D01*
X47641D01*
X48041Y-247600D01*
X47641Y-248000D01*
X48041D01*
X48441Y-248400D01*
Y-248000D02*
X48641Y-247800D01*
X48841D01*
X48641Y-247600D01*
X48841Y-247400D01*
X48641D01*
X48441Y-247200D01*
X48241Y-247400D01*
X48041D01*
X48241Y-247600D01*
X48041Y-247800D01*
X48241D01*
X48441Y-248000D01*
X50441Y-252400D02*
X50841Y-252000D01*
X51241D01*
X50841Y-251600D01*
X51241Y-251200D01*
X50841D01*
X50441Y-250800D01*
X50041Y-251200D01*
X49641D01*
X50041Y-251600D01*
X49641Y-252000D01*
X50041D01*
X50441Y-252400D01*
Y-252000D02*
X50641Y-251800D01*
X50841D01*
X50641Y-251600D01*
X50841Y-251400D01*
X50641D01*
X50441Y-251200D01*
X50241Y-251400D01*
X50041D01*
X50241Y-251600D01*
X50041Y-251800D01*
X50241D01*
X50441Y-252000D01*
Y-276400D02*
X50841Y-276000D01*
X51241D01*
X50841Y-275600D01*
X51241Y-275200D01*
X50841D01*
X50441Y-274800D01*
X50041Y-275200D01*
X49641D01*
X50041Y-275600D01*
X49641Y-276000D01*
X50041D01*
X50441Y-276400D01*
Y-276000D02*
X50641Y-275800D01*
X50841D01*
X50641Y-275600D01*
X50841Y-275400D01*
X50641D01*
X50441Y-275200D01*
X50241Y-275400D01*
X50041D01*
X50241Y-275600D01*
X50041Y-275800D01*
X50241D01*
X50441Y-276000D01*
X48441Y-280400D02*
X48841Y-280000D01*
X49241D01*
X48841Y-279600D01*
X49241Y-279200D01*
X48841D01*
X48441Y-278800D01*
X48041Y-279200D01*
X47641D01*
X48041Y-279600D01*
X47641Y-280000D01*
X48041D01*
X48441Y-280400D01*
Y-280000D02*
X48641Y-279800D01*
X48841D01*
X48641Y-279600D01*
X48841Y-279400D01*
X48641D01*
X48441Y-279200D01*
X48241Y-279400D01*
X48041D01*
X48241Y-279600D01*
X48041Y-279800D01*
X48241D01*
X48441Y-280000D01*
Y-288400D02*
X48841Y-288000D01*
X49241D01*
X48841Y-287600D01*
X49241Y-287200D01*
X48841D01*
X48441Y-286800D01*
X48041Y-287200D01*
X47641D01*
X48041Y-287600D01*
X47641Y-288000D01*
X48041D01*
X48441Y-288400D01*
Y-288000D02*
X48641Y-287800D01*
X48841D01*
X48641Y-287600D01*
X48841Y-287400D01*
X48641D01*
X48441Y-287200D01*
X48241Y-287400D01*
X48041D01*
X48241Y-287600D01*
X48041Y-287800D01*
X48241D01*
X48441Y-288000D01*
X50441Y-292400D02*
X50841Y-292000D01*
X51241D01*
X50841Y-291600D01*
X51241Y-291200D01*
X50841D01*
X50441Y-290800D01*
X50041Y-291200D01*
X49641D01*
X50041Y-291600D01*
X49641Y-292000D01*
X50041D01*
X50441Y-292400D01*
Y-292000D02*
X50641Y-291800D01*
X50841D01*
X50641Y-291600D01*
X50841Y-291400D01*
X50641D01*
X50441Y-291200D01*
X50241Y-291400D01*
X50041D01*
X50241Y-291600D01*
X50041Y-291800D01*
X50241D01*
X50441Y-292000D01*
Y-300400D02*
X50841Y-300000D01*
X51241D01*
X50841Y-299600D01*
X51241Y-299200D01*
X50841D01*
X50441Y-298800D01*
X50041Y-299200D01*
X49641D01*
X50041Y-299600D01*
X49641Y-300000D01*
X50041D01*
X50441Y-300400D01*
Y-300000D02*
X50641Y-299800D01*
X50841D01*
X50641Y-299600D01*
X50841Y-299400D01*
X50641D01*
X50441Y-299200D01*
X50241Y-299400D01*
X50041D01*
X50241Y-299600D01*
X50041Y-299800D01*
X50241D01*
X50441Y-300000D01*
X48441Y-304400D02*
X48841Y-304000D01*
X49241D01*
X48841Y-303600D01*
X49241Y-303200D01*
X48841D01*
X48441Y-302800D01*
X48041Y-303200D01*
X47641D01*
X48041Y-303600D01*
X47641Y-304000D01*
X48041D01*
X48441Y-304400D01*
Y-304000D02*
X48641Y-303800D01*
X48841D01*
X48641Y-303600D01*
X48841Y-303400D01*
X48641D01*
X48441Y-303200D01*
X48241Y-303400D01*
X48041D01*
X48241Y-303600D01*
X48041Y-303800D01*
X48241D01*
X48441Y-304000D01*
X50441Y-332400D02*
X50841Y-332000D01*
X51241D01*
X50841Y-331600D01*
X51241Y-331200D01*
X50841D01*
X50441Y-330800D01*
X50041Y-331200D01*
X49641D01*
X50041Y-331600D01*
X49641Y-332000D01*
X50041D01*
X50441Y-332400D01*
Y-332000D02*
X50641Y-331800D01*
X50841D01*
X50641Y-331600D01*
X50841Y-331400D01*
X50641D01*
X50441Y-331200D01*
X50241Y-331400D01*
X50041D01*
X50241Y-331600D01*
X50041Y-331800D01*
X50241D01*
X50441Y-332000D01*
X48441Y-336400D02*
X48841Y-336000D01*
X49241D01*
X48841Y-335600D01*
X49241Y-335200D01*
X48841D01*
X48441Y-334800D01*
X48041Y-335200D01*
X47641D01*
X48041Y-335600D01*
X47641Y-336000D01*
X48041D01*
X48441Y-336400D01*
Y-336000D02*
X48641Y-335800D01*
X48841D01*
X48641Y-335600D01*
X48841Y-335400D01*
X48641D01*
X48441Y-335200D01*
X48241Y-335400D01*
X48041D01*
X48241Y-335600D01*
X48041Y-335800D01*
X48241D01*
X48441Y-336000D01*
X50441Y-340400D02*
X50841Y-340000D01*
X51241D01*
X50841Y-339600D01*
X51241Y-339200D01*
X50841D01*
X50441Y-338800D01*
X50041Y-339200D01*
X49641D01*
X50041Y-339600D01*
X49641Y-340000D01*
X50041D01*
X50441Y-340400D01*
Y-340000D02*
X50641Y-339800D01*
X50841D01*
X50641Y-339600D01*
X50841Y-339400D01*
X50641D01*
X50441Y-339200D01*
X50241Y-339400D01*
X50041D01*
X50241Y-339600D01*
X50041Y-339800D01*
X50241D01*
X50441Y-340000D01*
X48441Y-344400D02*
X48841Y-344000D01*
X49241D01*
X48841Y-343600D01*
X49241Y-343200D01*
X48841D01*
X48441Y-342800D01*
X48041Y-343200D01*
X47641D01*
X48041Y-343600D01*
X47641Y-344000D01*
X48041D01*
X48441Y-344400D01*
Y-344000D02*
X48641Y-343800D01*
X48841D01*
X48641Y-343600D01*
X48841Y-343400D01*
X48641D01*
X48441Y-343200D01*
X48241Y-343400D01*
X48041D01*
X48241Y-343600D01*
X48041Y-343800D01*
X48241D01*
X48441Y-344000D01*
Y-352400D02*
X48841Y-352000D01*
X49241D01*
X48841Y-351600D01*
X49241Y-351200D01*
X48841D01*
X48441Y-350800D01*
X48041Y-351200D01*
X47641D01*
X48041Y-351600D01*
X47641Y-352000D01*
X48041D01*
X48441Y-352400D01*
Y-352000D02*
X48641Y-351800D01*
X48841D01*
X48641Y-351600D01*
X48841Y-351400D01*
X48641D01*
X48441Y-351200D01*
X48241Y-351400D01*
X48041D01*
X48241Y-351600D01*
X48041Y-351800D01*
X48241D01*
X48441Y-352000D01*
X46441Y-140400D02*
X46841Y-140000D01*
X47241D01*
X46841Y-139600D01*
X47241Y-139200D01*
X46841D01*
X46441Y-138800D01*
X46041Y-139200D01*
X45641D01*
X46041Y-139600D01*
X45641Y-140000D01*
X46041D01*
X46441Y-140400D01*
Y-140000D02*
X46641Y-139800D01*
X46841D01*
X46641Y-139600D01*
X46841Y-139400D01*
X46641D01*
X46441Y-139200D01*
X46241Y-139400D01*
X46041D01*
X46241Y-139600D01*
X46041Y-139800D01*
X46241D01*
X46441Y-140000D01*
X44441Y-144400D02*
X44841Y-144000D01*
X45241D01*
X44841Y-143600D01*
X45241Y-143200D01*
X44841D01*
X44441Y-142800D01*
X44041Y-143200D01*
X43641D01*
X44041Y-143600D01*
X43641Y-144000D01*
X44041D01*
X44441Y-144400D01*
Y-144000D02*
X44641Y-143800D01*
X44841D01*
X44641Y-143600D01*
X44841Y-143400D01*
X44641D01*
X44441Y-143200D01*
X44241Y-143400D01*
X44041D01*
X44241Y-143600D01*
X44041Y-143800D01*
X44241D01*
X44441Y-144000D01*
X46441Y-228400D02*
X46841Y-228000D01*
X47241D01*
X46841Y-227600D01*
X47241Y-227200D01*
X46841D01*
X46441Y-226800D01*
X46041Y-227200D01*
X45641D01*
X46041Y-227600D01*
X45641Y-228000D01*
X46041D01*
X46441Y-228400D01*
Y-228000D02*
X46641Y-227800D01*
X46841D01*
X46641Y-227600D01*
X46841Y-227400D01*
X46641D01*
X46441Y-227200D01*
X46241Y-227400D01*
X46041D01*
X46241Y-227600D01*
X46041Y-227800D01*
X46241D01*
X46441Y-228000D01*
X44441Y-232400D02*
X44841Y-232000D01*
X45241D01*
X44841Y-231600D01*
X45241Y-231200D01*
X44841D01*
X44441Y-230800D01*
X44041Y-231200D01*
X43641D01*
X44041Y-231600D01*
X43641Y-232000D01*
X44041D01*
X44441Y-232400D01*
Y-232000D02*
X44641Y-231800D01*
X44841D01*
X44641Y-231600D01*
X44841Y-231400D01*
X44641D01*
X44441Y-231200D01*
X44241Y-231400D01*
X44041D01*
X44241Y-231600D01*
X44041Y-231800D01*
X44241D01*
X44441Y-232000D01*
X46441Y-236400D02*
X46841Y-236000D01*
X47241D01*
X46841Y-235600D01*
X47241Y-235200D01*
X46841D01*
X46441Y-234800D01*
X46041Y-235200D01*
X45641D01*
X46041Y-235600D01*
X45641Y-236000D01*
X46041D01*
X46441Y-236400D01*
Y-236000D02*
X46641Y-235800D01*
X46841D01*
X46641Y-235600D01*
X46841Y-235400D01*
X46641D01*
X46441Y-235200D01*
X46241Y-235400D01*
X46041D01*
X46241Y-235600D01*
X46041Y-235800D01*
X46241D01*
X46441Y-236000D01*
Y-244400D02*
X46841Y-244000D01*
X47241D01*
X46841Y-243600D01*
X47241Y-243200D01*
X46841D01*
X46441Y-242800D01*
X46041Y-243200D01*
X45641D01*
X46041Y-243600D01*
X45641Y-244000D01*
X46041D01*
X46441Y-244400D01*
Y-244000D02*
X46641Y-243800D01*
X46841D01*
X46641Y-243600D01*
X46841Y-243400D01*
X46641D01*
X46441Y-243200D01*
X46241Y-243400D01*
X46041D01*
X46241Y-243600D01*
X46041Y-243800D01*
X46241D01*
X46441Y-244000D01*
X44441Y-248400D02*
X44841Y-248000D01*
X45241D01*
X44841Y-247600D01*
X45241Y-247200D01*
X44841D01*
X44441Y-246800D01*
X44041Y-247200D01*
X43641D01*
X44041Y-247600D01*
X43641Y-248000D01*
X44041D01*
X44441Y-248400D01*
Y-248000D02*
X44641Y-247800D01*
X44841D01*
X44641Y-247600D01*
X44841Y-247400D01*
X44641D01*
X44441Y-247200D01*
X44241Y-247400D01*
X44041D01*
X44241Y-247600D01*
X44041Y-247800D01*
X44241D01*
X44441Y-248000D01*
Y-280400D02*
X44841Y-280000D01*
X45241D01*
X44841Y-279600D01*
X45241Y-279200D01*
X44841D01*
X44441Y-278800D01*
X44041Y-279200D01*
X43641D01*
X44041Y-279600D01*
X43641Y-280000D01*
X44041D01*
X44441Y-280400D01*
Y-280000D02*
X44641Y-279800D01*
X44841D01*
X44641Y-279600D01*
X44841Y-279400D01*
X44641D01*
X44441Y-279200D01*
X44241Y-279400D01*
X44041D01*
X44241Y-279600D01*
X44041Y-279800D01*
X44241D01*
X44441Y-280000D01*
Y-288400D02*
X44841Y-288000D01*
X45241D01*
X44841Y-287600D01*
X45241Y-287200D01*
X44841D01*
X44441Y-286800D01*
X44041Y-287200D01*
X43641D01*
X44041Y-287600D01*
X43641Y-288000D01*
X44041D01*
X44441Y-288400D01*
Y-288000D02*
X44641Y-287800D01*
X44841D01*
X44641Y-287600D01*
X44841Y-287400D01*
X44641D01*
X44441Y-287200D01*
X44241Y-287400D01*
X44041D01*
X44241Y-287600D01*
X44041Y-287800D01*
X44241D01*
X44441Y-288000D01*
X46441Y-292400D02*
X46841Y-292000D01*
X47241D01*
X46841Y-291600D01*
X47241Y-291200D01*
X46841D01*
X46441Y-290800D01*
X46041Y-291200D01*
X45641D01*
X46041Y-291600D01*
X45641Y-292000D01*
X46041D01*
X46441Y-292400D01*
Y-292000D02*
X46641Y-291800D01*
X46841D01*
X46641Y-291600D01*
X46841Y-291400D01*
X46641D01*
X46441Y-291200D01*
X46241Y-291400D01*
X46041D01*
X46241Y-291600D01*
X46041Y-291800D01*
X46241D01*
X46441Y-292000D01*
Y-300400D02*
X46841Y-300000D01*
X47241D01*
X46841Y-299600D01*
X47241Y-299200D01*
X46841D01*
X46441Y-298800D01*
X46041Y-299200D01*
X45641D01*
X46041Y-299600D01*
X45641Y-300000D01*
X46041D01*
X46441Y-300400D01*
Y-300000D02*
X46641Y-299800D01*
X46841D01*
X46641Y-299600D01*
X46841Y-299400D01*
X46641D01*
X46441Y-299200D01*
X46241Y-299400D01*
X46041D01*
X46241Y-299600D01*
X46041Y-299800D01*
X46241D01*
X46441Y-300000D01*
Y-332400D02*
X46841Y-332000D01*
X47241D01*
X46841Y-331600D01*
X47241Y-331200D01*
X46841D01*
X46441Y-330800D01*
X46041Y-331200D01*
X45641D01*
X46041Y-331600D01*
X45641Y-332000D01*
X46041D01*
X46441Y-332400D01*
Y-332000D02*
X46641Y-331800D01*
X46841D01*
X46641Y-331600D01*
X46841Y-331400D01*
X46641D01*
X46441Y-331200D01*
X46241Y-331400D01*
X46041D01*
X46241Y-331600D01*
X46041Y-331800D01*
X46241D01*
X46441Y-332000D01*
X44441Y-336400D02*
X44841Y-336000D01*
X45241D01*
X44841Y-335600D01*
X45241Y-335200D01*
X44841D01*
X44441Y-334800D01*
X44041Y-335200D01*
X43641D01*
X44041Y-335600D01*
X43641Y-336000D01*
X44041D01*
X44441Y-336400D01*
Y-336000D02*
X44641Y-335800D01*
X44841D01*
X44641Y-335600D01*
X44841Y-335400D01*
X44641D01*
X44441Y-335200D01*
X44241Y-335400D01*
X44041D01*
X44241Y-335600D01*
X44041Y-335800D01*
X44241D01*
X44441Y-336000D01*
X46441Y-340400D02*
X46841Y-340000D01*
X47241D01*
X46841Y-339600D01*
X47241Y-339200D01*
X46841D01*
X46441Y-338800D01*
X46041Y-339200D01*
X45641D01*
X46041Y-339600D01*
X45641Y-340000D01*
X46041D01*
X46441Y-340400D01*
Y-340000D02*
X46641Y-339800D01*
X46841D01*
X46641Y-339600D01*
X46841Y-339400D01*
X46641D01*
X46441Y-339200D01*
X46241Y-339400D01*
X46041D01*
X46241Y-339600D01*
X46041Y-339800D01*
X46241D01*
X46441Y-340000D01*
X44441Y-344400D02*
X44841Y-344000D01*
X45241D01*
X44841Y-343600D01*
X45241Y-343200D01*
X44841D01*
X44441Y-342800D01*
X44041Y-343200D01*
X43641D01*
X44041Y-343600D01*
X43641Y-344000D01*
X44041D01*
X44441Y-344400D01*
Y-344000D02*
X44641Y-343800D01*
X44841D01*
X44641Y-343600D01*
X44841Y-343400D01*
X44641D01*
X44441Y-343200D01*
X44241Y-343400D01*
X44041D01*
X44241Y-343600D01*
X44041Y-343800D01*
X44241D01*
X44441Y-344000D01*
Y-352400D02*
X44841Y-352000D01*
X45241D01*
X44841Y-351600D01*
X45241Y-351200D01*
X44841D01*
X44441Y-350800D01*
X44041Y-351200D01*
X43641D01*
X44041Y-351600D01*
X43641Y-352000D01*
X44041D01*
X44441Y-352400D01*
Y-352000D02*
X44641Y-351800D01*
X44841D01*
X44641Y-351600D01*
X44841Y-351400D01*
X44641D01*
X44441Y-351200D01*
X44241Y-351400D01*
X44041D01*
X44241Y-351600D01*
X44041Y-351800D01*
X44241D01*
X44441Y-352000D01*
X42441Y-140400D02*
X42841Y-140000D01*
X43241D01*
X42841Y-139600D01*
X43241Y-139200D01*
X42841D01*
X42441Y-138800D01*
X42041Y-139200D01*
X41641D01*
X42041Y-139600D01*
X41641Y-140000D01*
X42041D01*
X42441Y-140400D01*
Y-140000D02*
X42641Y-139800D01*
X42841D01*
X42641Y-139600D01*
X42841Y-139400D01*
X42641D01*
X42441Y-139200D01*
X42241Y-139400D01*
X42041D01*
X42241Y-139600D01*
X42041Y-139800D01*
X42241D01*
X42441Y-140000D01*
X40441Y-144400D02*
X40841Y-144000D01*
X41241D01*
X40841Y-143600D01*
X41241Y-143200D01*
X40841D01*
X40441Y-142800D01*
X40041Y-143200D01*
X39641D01*
X40041Y-143600D01*
X39641Y-144000D01*
X40041D01*
X40441Y-144400D01*
Y-144000D02*
X40641Y-143800D01*
X40841D01*
X40641Y-143600D01*
X40841Y-143400D01*
X40641D01*
X40441Y-143200D01*
X40241Y-143400D01*
X40041D01*
X40241Y-143600D01*
X40041Y-143800D01*
X40241D01*
X40441Y-144000D01*
Y-224400D02*
X40841Y-224000D01*
X41241D01*
X40841Y-223600D01*
X41241Y-223200D01*
X40841D01*
X40441Y-222800D01*
X40041Y-223200D01*
X39641D01*
X40041Y-223600D01*
X39641Y-224000D01*
X40041D01*
X40441Y-224400D01*
Y-224000D02*
X40641Y-223800D01*
X40841D01*
X40641Y-223600D01*
X40841Y-223400D01*
X40641D01*
X40441Y-223200D01*
X40241Y-223400D01*
X40041D01*
X40241Y-223600D01*
X40041Y-223800D01*
X40241D01*
X40441Y-224000D01*
X42441Y-228400D02*
X42841Y-228000D01*
X43241D01*
X42841Y-227600D01*
X43241Y-227200D01*
X42841D01*
X42441Y-226800D01*
X42041Y-227200D01*
X41641D01*
X42041Y-227600D01*
X41641Y-228000D01*
X42041D01*
X42441Y-228400D01*
Y-228000D02*
X42641Y-227800D01*
X42841D01*
X42641Y-227600D01*
X42841Y-227400D01*
X42641D01*
X42441Y-227200D01*
X42241Y-227400D01*
X42041D01*
X42241Y-227600D01*
X42041Y-227800D01*
X42241D01*
X42441Y-228000D01*
X40441Y-232400D02*
X40841Y-232000D01*
X41241D01*
X40841Y-231600D01*
X41241Y-231200D01*
X40841D01*
X40441Y-230800D01*
X40041Y-231200D01*
X39641D01*
X40041Y-231600D01*
X39641Y-232000D01*
X40041D01*
X40441Y-232400D01*
Y-232000D02*
X40641Y-231800D01*
X40841D01*
X40641Y-231600D01*
X40841Y-231400D01*
X40641D01*
X40441Y-231200D01*
X40241Y-231400D01*
X40041D01*
X40241Y-231600D01*
X40041Y-231800D01*
X40241D01*
X40441Y-232000D01*
X42441Y-236400D02*
X42841Y-236000D01*
X43241D01*
X42841Y-235600D01*
X43241Y-235200D01*
X42841D01*
X42441Y-234800D01*
X42041Y-235200D01*
X41641D01*
X42041Y-235600D01*
X41641Y-236000D01*
X42041D01*
X42441Y-236400D01*
Y-236000D02*
X42641Y-235800D01*
X42841D01*
X42641Y-235600D01*
X42841Y-235400D01*
X42641D01*
X42441Y-235200D01*
X42241Y-235400D01*
X42041D01*
X42241Y-235600D01*
X42041Y-235800D01*
X42241D01*
X42441Y-236000D01*
Y-244400D02*
X42841Y-244000D01*
X43241D01*
X42841Y-243600D01*
X43241Y-243200D01*
X42841D01*
X42441Y-242800D01*
X42041Y-243200D01*
X41641D01*
X42041Y-243600D01*
X41641Y-244000D01*
X42041D01*
X42441Y-244400D01*
Y-244000D02*
X42641Y-243800D01*
X42841D01*
X42641Y-243600D01*
X42841Y-243400D01*
X42641D01*
X42441Y-243200D01*
X42241Y-243400D01*
X42041D01*
X42241Y-243600D01*
X42041Y-243800D01*
X42241D01*
X42441Y-244000D01*
X40441Y-248400D02*
X40841Y-248000D01*
X41241D01*
X40841Y-247600D01*
X41241Y-247200D01*
X40841D01*
X40441Y-246800D01*
X40041Y-247200D01*
X39641D01*
X40041Y-247600D01*
X39641Y-248000D01*
X40041D01*
X40441Y-248400D01*
Y-248000D02*
X40641Y-247800D01*
X40841D01*
X40641Y-247600D01*
X40841Y-247400D01*
X40641D01*
X40441Y-247200D01*
X40241Y-247400D01*
X40041D01*
X40241Y-247600D01*
X40041Y-247800D01*
X40241D01*
X40441Y-248000D01*
X42441Y-300400D02*
X42841Y-300000D01*
X43241D01*
X42841Y-299600D01*
X43241Y-299200D01*
X42841D01*
X42441Y-298800D01*
X42041Y-299200D01*
X41641D01*
X42041Y-299600D01*
X41641Y-300000D01*
X42041D01*
X42441Y-300400D01*
Y-300000D02*
X42641Y-299800D01*
X42841D01*
X42641Y-299600D01*
X42841Y-299400D01*
X42641D01*
X42441Y-299200D01*
X42241Y-299400D01*
X42041D01*
X42241Y-299600D01*
X42041Y-299800D01*
X42241D01*
X42441Y-300000D01*
Y-332400D02*
X42841Y-332000D01*
X43241D01*
X42841Y-331600D01*
X43241Y-331200D01*
X42841D01*
X42441Y-330800D01*
X42041Y-331200D01*
X41641D01*
X42041Y-331600D01*
X41641Y-332000D01*
X42041D01*
X42441Y-332400D01*
Y-332000D02*
X42641Y-331800D01*
X42841D01*
X42641Y-331600D01*
X42841Y-331400D01*
X42641D01*
X42441Y-331200D01*
X42241Y-331400D01*
X42041D01*
X42241Y-331600D01*
X42041Y-331800D01*
X42241D01*
X42441Y-332000D01*
X40441Y-336400D02*
X40841Y-336000D01*
X41241D01*
X40841Y-335600D01*
X41241Y-335200D01*
X40841D01*
X40441Y-334800D01*
X40041Y-335200D01*
X39641D01*
X40041Y-335600D01*
X39641Y-336000D01*
X40041D01*
X40441Y-336400D01*
Y-336000D02*
X40641Y-335800D01*
X40841D01*
X40641Y-335600D01*
X40841Y-335400D01*
X40641D01*
X40441Y-335200D01*
X40241Y-335400D01*
X40041D01*
X40241Y-335600D01*
X40041Y-335800D01*
X40241D01*
X40441Y-336000D01*
X42441Y-340400D02*
X42841Y-340000D01*
X43241D01*
X42841Y-339600D01*
X43241Y-339200D01*
X42841D01*
X42441Y-338800D01*
X42041Y-339200D01*
X41641D01*
X42041Y-339600D01*
X41641Y-340000D01*
X42041D01*
X42441Y-340400D01*
Y-340000D02*
X42641Y-339800D01*
X42841D01*
X42641Y-339600D01*
X42841Y-339400D01*
X42641D01*
X42441Y-339200D01*
X42241Y-339400D01*
X42041D01*
X42241Y-339600D01*
X42041Y-339800D01*
X42241D01*
X42441Y-340000D01*
X40441Y-344400D02*
X40841Y-344000D01*
X41241D01*
X40841Y-343600D01*
X41241Y-343200D01*
X40841D01*
X40441Y-342800D01*
X40041Y-343200D01*
X39641D01*
X40041Y-343600D01*
X39641Y-344000D01*
X40041D01*
X40441Y-344400D01*
Y-344000D02*
X40641Y-343800D01*
X40841D01*
X40641Y-343600D01*
X40841Y-343400D01*
X40641D01*
X40441Y-343200D01*
X40241Y-343400D01*
X40041D01*
X40241Y-343600D01*
X40041Y-343800D01*
X40241D01*
X40441Y-344000D01*
Y-352400D02*
X40841Y-352000D01*
X41241D01*
X40841Y-351600D01*
X41241Y-351200D01*
X40841D01*
X40441Y-350800D01*
X40041Y-351200D01*
X39641D01*
X40041Y-351600D01*
X39641Y-352000D01*
X40041D01*
X40441Y-352400D01*
Y-352000D02*
X40641Y-351800D01*
X40841D01*
X40641Y-351600D01*
X40841Y-351400D01*
X40641D01*
X40441Y-351200D01*
X40241Y-351400D01*
X40041D01*
X40241Y-351600D01*
X40041Y-351800D01*
X40241D01*
X40441Y-352000D01*
X38441Y-140400D02*
X38841Y-140000D01*
X39241D01*
X38841Y-139600D01*
X39241Y-139200D01*
X38841D01*
X38441Y-138800D01*
X38041Y-139200D01*
X37641D01*
X38041Y-139600D01*
X37641Y-140000D01*
X38041D01*
X38441Y-140400D01*
Y-140000D02*
X38641Y-139800D01*
X38841D01*
X38641Y-139600D01*
X38841Y-139400D01*
X38641D01*
X38441Y-139200D01*
X38241Y-139400D01*
X38041D01*
X38241Y-139600D01*
X38041Y-139800D01*
X38241D01*
X38441Y-140000D01*
X36441Y-144400D02*
X36841Y-144000D01*
X37241D01*
X36841Y-143600D01*
X37241Y-143200D01*
X36841D01*
X36441Y-142800D01*
X36041Y-143200D01*
X35641D01*
X36041Y-143600D01*
X35641Y-144000D01*
X36041D01*
X36441Y-144400D01*
Y-144000D02*
X36641Y-143800D01*
X36841D01*
X36641Y-143600D01*
X36841Y-143400D01*
X36641D01*
X36441Y-143200D01*
X36241Y-143400D01*
X36041D01*
X36241Y-143600D01*
X36041Y-143800D01*
X36241D01*
X36441Y-144000D01*
Y-152400D02*
X36841Y-152000D01*
X37241D01*
X36841Y-151600D01*
X37241Y-151200D01*
X36841D01*
X36441Y-150800D01*
X36041Y-151200D01*
X35641D01*
X36041Y-151600D01*
X35641Y-152000D01*
X36041D01*
X36441Y-152400D01*
Y-152000D02*
X36641Y-151800D01*
X36841D01*
X36641Y-151600D01*
X36841Y-151400D01*
X36641D01*
X36441Y-151200D01*
X36241Y-151400D01*
X36041D01*
X36241Y-151600D01*
X36041Y-151800D01*
X36241D01*
X36441Y-152000D01*
Y-216400D02*
X36841Y-216000D01*
X37241D01*
X36841Y-215600D01*
X37241Y-215200D01*
X36841D01*
X36441Y-214800D01*
X36041Y-215200D01*
X35641D01*
X36041Y-215600D01*
X35641Y-216000D01*
X36041D01*
X36441Y-216400D01*
Y-216000D02*
X36641Y-215800D01*
X36841D01*
X36641Y-215600D01*
X36841Y-215400D01*
X36641D01*
X36441Y-215200D01*
X36241Y-215400D01*
X36041D01*
X36241Y-215600D01*
X36041Y-215800D01*
X36241D01*
X36441Y-216000D01*
Y-224400D02*
X36841Y-224000D01*
X37241D01*
X36841Y-223600D01*
X37241Y-223200D01*
X36841D01*
X36441Y-222800D01*
X36041Y-223200D01*
X35641D01*
X36041Y-223600D01*
X35641Y-224000D01*
X36041D01*
X36441Y-224400D01*
Y-224000D02*
X36641Y-223800D01*
X36841D01*
X36641Y-223600D01*
X36841Y-223400D01*
X36641D01*
X36441Y-223200D01*
X36241Y-223400D01*
X36041D01*
X36241Y-223600D01*
X36041Y-223800D01*
X36241D01*
X36441Y-224000D01*
X38441Y-228400D02*
X38841Y-228000D01*
X39241D01*
X38841Y-227600D01*
X39241Y-227200D01*
X38841D01*
X38441Y-226800D01*
X38041Y-227200D01*
X37641D01*
X38041Y-227600D01*
X37641Y-228000D01*
X38041D01*
X38441Y-228400D01*
Y-228000D02*
X38641Y-227800D01*
X38841D01*
X38641Y-227600D01*
X38841Y-227400D01*
X38641D01*
X38441Y-227200D01*
X38241Y-227400D01*
X38041D01*
X38241Y-227600D01*
X38041Y-227800D01*
X38241D01*
X38441Y-228000D01*
X36441Y-232400D02*
X36841Y-232000D01*
X37241D01*
X36841Y-231600D01*
X37241Y-231200D01*
X36841D01*
X36441Y-230800D01*
X36041Y-231200D01*
X35641D01*
X36041Y-231600D01*
X35641Y-232000D01*
X36041D01*
X36441Y-232400D01*
Y-232000D02*
X36641Y-231800D01*
X36841D01*
X36641Y-231600D01*
X36841Y-231400D01*
X36641D01*
X36441Y-231200D01*
X36241Y-231400D01*
X36041D01*
X36241Y-231600D01*
X36041Y-231800D01*
X36241D01*
X36441Y-232000D01*
X38441Y-236400D02*
X38841Y-236000D01*
X39241D01*
X38841Y-235600D01*
X39241Y-235200D01*
X38841D01*
X38441Y-234800D01*
X38041Y-235200D01*
X37641D01*
X38041Y-235600D01*
X37641Y-236000D01*
X38041D01*
X38441Y-236400D01*
Y-236000D02*
X38641Y-235800D01*
X38841D01*
X38641Y-235600D01*
X38841Y-235400D01*
X38641D01*
X38441Y-235200D01*
X38241Y-235400D01*
X38041D01*
X38241Y-235600D01*
X38041Y-235800D01*
X38241D01*
X38441Y-236000D01*
Y-244400D02*
X38841Y-244000D01*
X39241D01*
X38841Y-243600D01*
X39241Y-243200D01*
X38841D01*
X38441Y-242800D01*
X38041Y-243200D01*
X37641D01*
X38041Y-243600D01*
X37641Y-244000D01*
X38041D01*
X38441Y-244400D01*
Y-244000D02*
X38641Y-243800D01*
X38841D01*
X38641Y-243600D01*
X38841Y-243400D01*
X38641D01*
X38441Y-243200D01*
X38241Y-243400D01*
X38041D01*
X38241Y-243600D01*
X38041Y-243800D01*
X38241D01*
X38441Y-244000D01*
X36441Y-248400D02*
X36841Y-248000D01*
X37241D01*
X36841Y-247600D01*
X37241Y-247200D01*
X36841D01*
X36441Y-246800D01*
X36041Y-247200D01*
X35641D01*
X36041Y-247600D01*
X35641Y-248000D01*
X36041D01*
X36441Y-248400D01*
Y-248000D02*
X36641Y-247800D01*
X36841D01*
X36641Y-247600D01*
X36841Y-247400D01*
X36641D01*
X36441Y-247200D01*
X36241Y-247400D01*
X36041D01*
X36241Y-247600D01*
X36041Y-247800D01*
X36241D01*
X36441Y-248000D01*
X38441Y-252400D02*
X38841Y-252000D01*
X39241D01*
X38841Y-251600D01*
X39241Y-251200D01*
X38841D01*
X38441Y-250800D01*
X38041Y-251200D01*
X37641D01*
X38041Y-251600D01*
X37641Y-252000D01*
X38041D01*
X38441Y-252400D01*
Y-252000D02*
X38641Y-251800D01*
X38841D01*
X38641Y-251600D01*
X38841Y-251400D01*
X38641D01*
X38441Y-251200D01*
X38241Y-251400D01*
X38041D01*
X38241Y-251600D01*
X38041Y-251800D01*
X38241D01*
X38441Y-252000D01*
X36441Y-256400D02*
X36841Y-256000D01*
X37241D01*
X36841Y-255600D01*
X37241Y-255200D01*
X36841D01*
X36441Y-254800D01*
X36041Y-255200D01*
X35641D01*
X36041Y-255600D01*
X35641Y-256000D01*
X36041D01*
X36441Y-256400D01*
Y-256000D02*
X36641Y-255800D01*
X36841D01*
X36641Y-255600D01*
X36841Y-255400D01*
X36641D01*
X36441Y-255200D01*
X36241Y-255400D01*
X36041D01*
X36241Y-255600D01*
X36041Y-255800D01*
X36241D01*
X36441Y-256000D01*
Y-328400D02*
X36841Y-328000D01*
X37241D01*
X36841Y-327600D01*
X37241Y-327200D01*
X36841D01*
X36441Y-326800D01*
X36041Y-327200D01*
X35641D01*
X36041Y-327600D01*
X35641Y-328000D01*
X36041D01*
X36441Y-328400D01*
Y-328000D02*
X36641Y-327800D01*
X36841D01*
X36641Y-327600D01*
X36841Y-327400D01*
X36641D01*
X36441Y-327200D01*
X36241Y-327400D01*
X36041D01*
X36241Y-327600D01*
X36041Y-327800D01*
X36241D01*
X36441Y-328000D01*
X38441Y-332400D02*
X38841Y-332000D01*
X39241D01*
X38841Y-331600D01*
X39241Y-331200D01*
X38841D01*
X38441Y-330800D01*
X38041Y-331200D01*
X37641D01*
X38041Y-331600D01*
X37641Y-332000D01*
X38041D01*
X38441Y-332400D01*
Y-332000D02*
X38641Y-331800D01*
X38841D01*
X38641Y-331600D01*
X38841Y-331400D01*
X38641D01*
X38441Y-331200D01*
X38241Y-331400D01*
X38041D01*
X38241Y-331600D01*
X38041Y-331800D01*
X38241D01*
X38441Y-332000D01*
X36441Y-336400D02*
X36841Y-336000D01*
X37241D01*
X36841Y-335600D01*
X37241Y-335200D01*
X36841D01*
X36441Y-334800D01*
X36041Y-335200D01*
X35641D01*
X36041Y-335600D01*
X35641Y-336000D01*
X36041D01*
X36441Y-336400D01*
Y-336000D02*
X36641Y-335800D01*
X36841D01*
X36641Y-335600D01*
X36841Y-335400D01*
X36641D01*
X36441Y-335200D01*
X36241Y-335400D01*
X36041D01*
X36241Y-335600D01*
X36041Y-335800D01*
X36241D01*
X36441Y-336000D01*
X38441Y-340400D02*
X38841Y-340000D01*
X39241D01*
X38841Y-339600D01*
X39241Y-339200D01*
X38841D01*
X38441Y-338800D01*
X38041Y-339200D01*
X37641D01*
X38041Y-339600D01*
X37641Y-340000D01*
X38041D01*
X38441Y-340400D01*
Y-340000D02*
X38641Y-339800D01*
X38841D01*
X38641Y-339600D01*
X38841Y-339400D01*
X38641D01*
X38441Y-339200D01*
X38241Y-339400D01*
X38041D01*
X38241Y-339600D01*
X38041Y-339800D01*
X38241D01*
X38441Y-340000D01*
X36441Y-344400D02*
X36841Y-344000D01*
X37241D01*
X36841Y-343600D01*
X37241Y-343200D01*
X36841D01*
X36441Y-342800D01*
X36041Y-343200D01*
X35641D01*
X36041Y-343600D01*
X35641Y-344000D01*
X36041D01*
X36441Y-344400D01*
Y-344000D02*
X36641Y-343800D01*
X36841D01*
X36641Y-343600D01*
X36841Y-343400D01*
X36641D01*
X36441Y-343200D01*
X36241Y-343400D01*
X36041D01*
X36241Y-343600D01*
X36041Y-343800D01*
X36241D01*
X36441Y-344000D01*
Y-352400D02*
X36841Y-352000D01*
X37241D01*
X36841Y-351600D01*
X37241Y-351200D01*
X36841D01*
X36441Y-350800D01*
X36041Y-351200D01*
X35641D01*
X36041Y-351600D01*
X35641Y-352000D01*
X36041D01*
X36441Y-352400D01*
Y-352000D02*
X36641Y-351800D01*
X36841D01*
X36641Y-351600D01*
X36841Y-351400D01*
X36641D01*
X36441Y-351200D01*
X36241Y-351400D01*
X36041D01*
X36241Y-351600D01*
X36041Y-351800D01*
X36241D01*
X36441Y-352000D01*
X34441Y-140400D02*
X34841Y-140000D01*
X35241D01*
X34841Y-139600D01*
X35241Y-139200D01*
X34841D01*
X34441Y-138800D01*
X34041Y-139200D01*
X33641D01*
X34041Y-139600D01*
X33641Y-140000D01*
X34041D01*
X34441Y-140400D01*
Y-140000D02*
X34641Y-139800D01*
X34841D01*
X34641Y-139600D01*
X34841Y-139400D01*
X34641D01*
X34441Y-139200D01*
X34241Y-139400D01*
X34041D01*
X34241Y-139600D01*
X34041Y-139800D01*
X34241D01*
X34441Y-140000D01*
X32441Y-144400D02*
X32841Y-144000D01*
X33241D01*
X32841Y-143600D01*
X33241Y-143200D01*
X32841D01*
X32441Y-142800D01*
X32041Y-143200D01*
X31641D01*
X32041Y-143600D01*
X31641Y-144000D01*
X32041D01*
X32441Y-144400D01*
Y-144000D02*
X32641Y-143800D01*
X32841D01*
X32641Y-143600D01*
X32841Y-143400D01*
X32641D01*
X32441Y-143200D01*
X32241Y-143400D01*
X32041D01*
X32241Y-143600D01*
X32041Y-143800D01*
X32241D01*
X32441Y-144000D01*
X34441Y-148400D02*
X34841Y-148000D01*
X35241D01*
X34841Y-147600D01*
X35241Y-147200D01*
X34841D01*
X34441Y-146800D01*
X34041Y-147200D01*
X33641D01*
X34041Y-147600D01*
X33641Y-148000D01*
X34041D01*
X34441Y-148400D01*
Y-148000D02*
X34641Y-147800D01*
X34841D01*
X34641Y-147600D01*
X34841Y-147400D01*
X34641D01*
X34441Y-147200D01*
X34241Y-147400D01*
X34041D01*
X34241Y-147600D01*
X34041Y-147800D01*
X34241D01*
X34441Y-148000D01*
X32441Y-152400D02*
X32841Y-152000D01*
X33241D01*
X32841Y-151600D01*
X33241Y-151200D01*
X32841D01*
X32441Y-150800D01*
X32041Y-151200D01*
X31641D01*
X32041Y-151600D01*
X31641Y-152000D01*
X32041D01*
X32441Y-152400D01*
Y-152000D02*
X32641Y-151800D01*
X32841D01*
X32641Y-151600D01*
X32841Y-151400D01*
X32641D01*
X32441Y-151200D01*
X32241Y-151400D01*
X32041D01*
X32241Y-151600D01*
X32041Y-151800D01*
X32241D01*
X32441Y-152000D01*
X34441Y-164400D02*
X34841Y-164000D01*
X35241D01*
X34841Y-163600D01*
X35241Y-163200D01*
X34841D01*
X34441Y-162800D01*
X34041Y-163200D01*
X33641D01*
X34041Y-163600D01*
X33641Y-164000D01*
X34041D01*
X34441Y-164400D01*
Y-164000D02*
X34641Y-163800D01*
X34841D01*
X34641Y-163600D01*
X34841Y-163400D01*
X34641D01*
X34441Y-163200D01*
X34241Y-163400D01*
X34041D01*
X34241Y-163600D01*
X34041Y-163800D01*
X34241D01*
X34441Y-164000D01*
Y-220400D02*
X34841Y-220000D01*
X35241D01*
X34841Y-219600D01*
X35241Y-219200D01*
X34841D01*
X34441Y-218800D01*
X34041Y-219200D01*
X33641D01*
X34041Y-219600D01*
X33641Y-220000D01*
X34041D01*
X34441Y-220400D01*
Y-220000D02*
X34641Y-219800D01*
X34841D01*
X34641Y-219600D01*
X34841Y-219400D01*
X34641D01*
X34441Y-219200D01*
X34241Y-219400D01*
X34041D01*
X34241Y-219600D01*
X34041Y-219800D01*
X34241D01*
X34441Y-220000D01*
Y-228400D02*
X34841Y-228000D01*
X35241D01*
X34841Y-227600D01*
X35241Y-227200D01*
X34841D01*
X34441Y-226800D01*
X34041Y-227200D01*
X33641D01*
X34041Y-227600D01*
X33641Y-228000D01*
X34041D01*
X34441Y-228400D01*
Y-228000D02*
X34641Y-227800D01*
X34841D01*
X34641Y-227600D01*
X34841Y-227400D01*
X34641D01*
X34441Y-227200D01*
X34241Y-227400D01*
X34041D01*
X34241Y-227600D01*
X34041Y-227800D01*
X34241D01*
X34441Y-228000D01*
Y-236400D02*
X34841Y-236000D01*
X35241D01*
X34841Y-235600D01*
X35241Y-235200D01*
X34841D01*
X34441Y-234800D01*
X34041Y-235200D01*
X33641D01*
X34041Y-235600D01*
X33641Y-236000D01*
X34041D01*
X34441Y-236400D01*
Y-236000D02*
X34641Y-235800D01*
X34841D01*
X34641Y-235600D01*
X34841Y-235400D01*
X34641D01*
X34441Y-235200D01*
X34241Y-235400D01*
X34041D01*
X34241Y-235600D01*
X34041Y-235800D01*
X34241D01*
X34441Y-236000D01*
Y-244400D02*
X34841Y-244000D01*
X35241D01*
X34841Y-243600D01*
X35241Y-243200D01*
X34841D01*
X34441Y-242800D01*
X34041Y-243200D01*
X33641D01*
X34041Y-243600D01*
X33641Y-244000D01*
X34041D01*
X34441Y-244400D01*
Y-244000D02*
X34641Y-243800D01*
X34841D01*
X34641Y-243600D01*
X34841Y-243400D01*
X34641D01*
X34441Y-243200D01*
X34241Y-243400D01*
X34041D01*
X34241Y-243600D01*
X34041Y-243800D01*
X34241D01*
X34441Y-244000D01*
Y-252400D02*
X34841Y-252000D01*
X35241D01*
X34841Y-251600D01*
X35241Y-251200D01*
X34841D01*
X34441Y-250800D01*
X34041Y-251200D01*
X33641D01*
X34041Y-251600D01*
X33641Y-252000D01*
X34041D01*
X34441Y-252400D01*
Y-252000D02*
X34641Y-251800D01*
X34841D01*
X34641Y-251600D01*
X34841Y-251400D01*
X34641D01*
X34441Y-251200D01*
X34241Y-251400D01*
X34041D01*
X34241Y-251600D01*
X34041Y-251800D01*
X34241D01*
X34441Y-252000D01*
Y-268400D02*
X34841Y-268000D01*
X35241D01*
X34841Y-267600D01*
X35241Y-267200D01*
X34841D01*
X34441Y-266800D01*
X34041Y-267200D01*
X33641D01*
X34041Y-267600D01*
X33641Y-268000D01*
X34041D01*
X34441Y-268400D01*
Y-268000D02*
X34641Y-267800D01*
X34841D01*
X34641Y-267600D01*
X34841Y-267400D01*
X34641D01*
X34441Y-267200D01*
X34241Y-267400D01*
X34041D01*
X34241Y-267600D01*
X34041Y-267800D01*
X34241D01*
X34441Y-268000D01*
Y-276400D02*
X34841Y-276000D01*
X35241D01*
X34841Y-275600D01*
X35241Y-275200D01*
X34841D01*
X34441Y-274800D01*
X34041Y-275200D01*
X33641D01*
X34041Y-275600D01*
X33641Y-276000D01*
X34041D01*
X34441Y-276400D01*
Y-276000D02*
X34641Y-275800D01*
X34841D01*
X34641Y-275600D01*
X34841Y-275400D01*
X34641D01*
X34441Y-275200D01*
X34241Y-275400D01*
X34041D01*
X34241Y-275600D01*
X34041Y-275800D01*
X34241D01*
X34441Y-276000D01*
Y-300400D02*
X34841Y-300000D01*
X35241D01*
X34841Y-299600D01*
X35241Y-299200D01*
X34841D01*
X34441Y-298800D01*
X34041Y-299200D01*
X33641D01*
X34041Y-299600D01*
X33641Y-300000D01*
X34041D01*
X34441Y-300400D01*
Y-300000D02*
X34641Y-299800D01*
X34841D01*
X34641Y-299600D01*
X34841Y-299400D01*
X34641D01*
X34441Y-299200D01*
X34241Y-299400D01*
X34041D01*
X34241Y-299600D01*
X34041Y-299800D01*
X34241D01*
X34441Y-300000D01*
Y-308400D02*
X34841Y-308000D01*
X35241D01*
X34841Y-307600D01*
X35241Y-307200D01*
X34841D01*
X34441Y-306800D01*
X34041Y-307200D01*
X33641D01*
X34041Y-307600D01*
X33641Y-308000D01*
X34041D01*
X34441Y-308400D01*
Y-308000D02*
X34641Y-307800D01*
X34841D01*
X34641Y-307600D01*
X34841Y-307400D01*
X34641D01*
X34441Y-307200D01*
X34241Y-307400D01*
X34041D01*
X34241Y-307600D01*
X34041Y-307800D01*
X34241D01*
X34441Y-308000D01*
Y-324400D02*
X34841Y-324000D01*
X35241D01*
X34841Y-323600D01*
X35241Y-323200D01*
X34841D01*
X34441Y-322800D01*
X34041Y-323200D01*
X33641D01*
X34041Y-323600D01*
X33641Y-324000D01*
X34041D01*
X34441Y-324400D01*
Y-324000D02*
X34641Y-323800D01*
X34841D01*
X34641Y-323600D01*
X34841Y-323400D01*
X34641D01*
X34441Y-323200D01*
X34241Y-323400D01*
X34041D01*
X34241Y-323600D01*
X34041Y-323800D01*
X34241D01*
X34441Y-324000D01*
X32441Y-328400D02*
X32841Y-328000D01*
X33241D01*
X32841Y-327600D01*
X33241Y-327200D01*
X32841D01*
X32441Y-326800D01*
X32041Y-327200D01*
X31641D01*
X32041Y-327600D01*
X31641Y-328000D01*
X32041D01*
X32441Y-328400D01*
Y-328000D02*
X32641Y-327800D01*
X32841D01*
X32641Y-327600D01*
X32841Y-327400D01*
X32641D01*
X32441Y-327200D01*
X32241Y-327400D01*
X32041D01*
X32241Y-327600D01*
X32041Y-327800D01*
X32241D01*
X32441Y-328000D01*
X34441Y-332400D02*
X34841Y-332000D01*
X35241D01*
X34841Y-331600D01*
X35241Y-331200D01*
X34841D01*
X34441Y-330800D01*
X34041Y-331200D01*
X33641D01*
X34041Y-331600D01*
X33641Y-332000D01*
X34041D01*
X34441Y-332400D01*
Y-332000D02*
X34641Y-331800D01*
X34841D01*
X34641Y-331600D01*
X34841Y-331400D01*
X34641D01*
X34441Y-331200D01*
X34241Y-331400D01*
X34041D01*
X34241Y-331600D01*
X34041Y-331800D01*
X34241D01*
X34441Y-332000D01*
X32441Y-336400D02*
X32841Y-336000D01*
X33241D01*
X32841Y-335600D01*
X33241Y-335200D01*
X32841D01*
X32441Y-334800D01*
X32041Y-335200D01*
X31641D01*
X32041Y-335600D01*
X31641Y-336000D01*
X32041D01*
X32441Y-336400D01*
Y-336000D02*
X32641Y-335800D01*
X32841D01*
X32641Y-335600D01*
X32841Y-335400D01*
X32641D01*
X32441Y-335200D01*
X32241Y-335400D01*
X32041D01*
X32241Y-335600D01*
X32041Y-335800D01*
X32241D01*
X32441Y-336000D01*
X34441Y-340400D02*
X34841Y-340000D01*
X35241D01*
X34841Y-339600D01*
X35241Y-339200D01*
X34841D01*
X34441Y-338800D01*
X34041Y-339200D01*
X33641D01*
X34041Y-339600D01*
X33641Y-340000D01*
X34041D01*
X34441Y-340400D01*
Y-340000D02*
X34641Y-339800D01*
X34841D01*
X34641Y-339600D01*
X34841Y-339400D01*
X34641D01*
X34441Y-339200D01*
X34241Y-339400D01*
X34041D01*
X34241Y-339600D01*
X34041Y-339800D01*
X34241D01*
X34441Y-340000D01*
X32441Y-344400D02*
X32841Y-344000D01*
X33241D01*
X32841Y-343600D01*
X33241Y-343200D01*
X32841D01*
X32441Y-342800D01*
X32041Y-343200D01*
X31641D01*
X32041Y-343600D01*
X31641Y-344000D01*
X32041D01*
X32441Y-344400D01*
Y-344000D02*
X32641Y-343800D01*
X32841D01*
X32641Y-343600D01*
X32841Y-343400D01*
X32641D01*
X32441Y-343200D01*
X32241Y-343400D01*
X32041D01*
X32241Y-343600D01*
X32041Y-343800D01*
X32241D01*
X32441Y-344000D01*
Y-352400D02*
X32841Y-352000D01*
X33241D01*
X32841Y-351600D01*
X33241Y-351200D01*
X32841D01*
X32441Y-350800D01*
X32041Y-351200D01*
X31641D01*
X32041Y-351600D01*
X31641Y-352000D01*
X32041D01*
X32441Y-352400D01*
Y-352000D02*
X32641Y-351800D01*
X32841D01*
X32641Y-351600D01*
X32841Y-351400D01*
X32641D01*
X32441Y-351200D01*
X32241Y-351400D01*
X32041D01*
X32241Y-351600D01*
X32041Y-351800D01*
X32241D01*
X32441Y-352000D01*
X30441Y-140400D02*
X30841Y-140000D01*
X31241D01*
X30841Y-139600D01*
X31241Y-139200D01*
X30841D01*
X30441Y-138800D01*
X30041Y-139200D01*
X29641D01*
X30041Y-139600D01*
X29641Y-140000D01*
X30041D01*
X30441Y-140400D01*
Y-140000D02*
X30641Y-139800D01*
X30841D01*
X30641Y-139600D01*
X30841Y-139400D01*
X30641D01*
X30441Y-139200D01*
X30241Y-139400D01*
X30041D01*
X30241Y-139600D01*
X30041Y-139800D01*
X30241D01*
X30441Y-140000D01*
X28441Y-144400D02*
X28841Y-144000D01*
X29241D01*
X28841Y-143600D01*
X29241Y-143200D01*
X28841D01*
X28441Y-142800D01*
X28041Y-143200D01*
X27641D01*
X28041Y-143600D01*
X27641Y-144000D01*
X28041D01*
X28441Y-144400D01*
Y-144000D02*
X28641Y-143800D01*
X28841D01*
X28641Y-143600D01*
X28841Y-143400D01*
X28641D01*
X28441Y-143200D01*
X28241Y-143400D01*
X28041D01*
X28241Y-143600D01*
X28041Y-143800D01*
X28241D01*
X28441Y-144000D01*
X30441Y-148400D02*
X30841Y-148000D01*
X31241D01*
X30841Y-147600D01*
X31241Y-147200D01*
X30841D01*
X30441Y-146800D01*
X30041Y-147200D01*
X29641D01*
X30041Y-147600D01*
X29641Y-148000D01*
X30041D01*
X30441Y-148400D01*
Y-148000D02*
X30641Y-147800D01*
X30841D01*
X30641Y-147600D01*
X30841Y-147400D01*
X30641D01*
X30441Y-147200D01*
X30241Y-147400D01*
X30041D01*
X30241Y-147600D01*
X30041Y-147800D01*
X30241D01*
X30441Y-148000D01*
X28441Y-152400D02*
X28841Y-152000D01*
X29241D01*
X28841Y-151600D01*
X29241Y-151200D01*
X28841D01*
X28441Y-150800D01*
X28041Y-151200D01*
X27641D01*
X28041Y-151600D01*
X27641Y-152000D01*
X28041D01*
X28441Y-152400D01*
Y-152000D02*
X28641Y-151800D01*
X28841D01*
X28641Y-151600D01*
X28841Y-151400D01*
X28641D01*
X28441Y-151200D01*
X28241Y-151400D01*
X28041D01*
X28241Y-151600D01*
X28041Y-151800D01*
X28241D01*
X28441Y-152000D01*
X30441Y-164400D02*
X30841Y-164000D01*
X31241D01*
X30841Y-163600D01*
X31241Y-163200D01*
X30841D01*
X30441Y-162800D01*
X30041Y-163200D01*
X29641D01*
X30041Y-163600D01*
X29641Y-164000D01*
X30041D01*
X30441Y-164400D01*
Y-164000D02*
X30641Y-163800D01*
X30841D01*
X30641Y-163600D01*
X30841Y-163400D01*
X30641D01*
X30441Y-163200D01*
X30241Y-163400D01*
X30041D01*
X30241Y-163600D01*
X30041Y-163800D01*
X30241D01*
X30441Y-164000D01*
X28441Y-168400D02*
X28841Y-168000D01*
X29241D01*
X28841Y-167600D01*
X29241Y-167200D01*
X28841D01*
X28441Y-166800D01*
X28041Y-167200D01*
X27641D01*
X28041Y-167600D01*
X27641Y-168000D01*
X28041D01*
X28441Y-168400D01*
Y-168000D02*
X28641Y-167800D01*
X28841D01*
X28641Y-167600D01*
X28841Y-167400D01*
X28641D01*
X28441Y-167200D01*
X28241Y-167400D01*
X28041D01*
X28241Y-167600D01*
X28041Y-167800D01*
X28241D01*
X28441Y-168000D01*
Y-328400D02*
X28841Y-328000D01*
X29241D01*
X28841Y-327600D01*
X29241Y-327200D01*
X28841D01*
X28441Y-326800D01*
X28041Y-327200D01*
X27641D01*
X28041Y-327600D01*
X27641Y-328000D01*
X28041D01*
X28441Y-328400D01*
Y-328000D02*
X28641Y-327800D01*
X28841D01*
X28641Y-327600D01*
X28841Y-327400D01*
X28641D01*
X28441Y-327200D01*
X28241Y-327400D01*
X28041D01*
X28241Y-327600D01*
X28041Y-327800D01*
X28241D01*
X28441Y-328000D01*
X30441Y-332400D02*
X30841Y-332000D01*
X31241D01*
X30841Y-331600D01*
X31241Y-331200D01*
X30841D01*
X30441Y-330800D01*
X30041Y-331200D01*
X29641D01*
X30041Y-331600D01*
X29641Y-332000D01*
X30041D01*
X30441Y-332400D01*
Y-332000D02*
X30641Y-331800D01*
X30841D01*
X30641Y-331600D01*
X30841Y-331400D01*
X30641D01*
X30441Y-331200D01*
X30241Y-331400D01*
X30041D01*
X30241Y-331600D01*
X30041Y-331800D01*
X30241D01*
X30441Y-332000D01*
X28441Y-336400D02*
X28841Y-336000D01*
X29241D01*
X28841Y-335600D01*
X29241Y-335200D01*
X28841D01*
X28441Y-334800D01*
X28041Y-335200D01*
X27641D01*
X28041Y-335600D01*
X27641Y-336000D01*
X28041D01*
X28441Y-336400D01*
Y-336000D02*
X28641Y-335800D01*
X28841D01*
X28641Y-335600D01*
X28841Y-335400D01*
X28641D01*
X28441Y-335200D01*
X28241Y-335400D01*
X28041D01*
X28241Y-335600D01*
X28041Y-335800D01*
X28241D01*
X28441Y-336000D01*
X30441Y-340400D02*
X30841Y-340000D01*
X31241D01*
X30841Y-339600D01*
X31241Y-339200D01*
X30841D01*
X30441Y-338800D01*
X30041Y-339200D01*
X29641D01*
X30041Y-339600D01*
X29641Y-340000D01*
X30041D01*
X30441Y-340400D01*
Y-340000D02*
X30641Y-339800D01*
X30841D01*
X30641Y-339600D01*
X30841Y-339400D01*
X30641D01*
X30441Y-339200D01*
X30241Y-339400D01*
X30041D01*
X30241Y-339600D01*
X30041Y-339800D01*
X30241D01*
X30441Y-340000D01*
X28441Y-344400D02*
X28841Y-344000D01*
X29241D01*
X28841Y-343600D01*
X29241Y-343200D01*
X28841D01*
X28441Y-342800D01*
X28041Y-343200D01*
X27641D01*
X28041Y-343600D01*
X27641Y-344000D01*
X28041D01*
X28441Y-344400D01*
Y-344000D02*
X28641Y-343800D01*
X28841D01*
X28641Y-343600D01*
X28841Y-343400D01*
X28641D01*
X28441Y-343200D01*
X28241Y-343400D01*
X28041D01*
X28241Y-343600D01*
X28041Y-343800D01*
X28241D01*
X28441Y-344000D01*
Y-352400D02*
X28841Y-352000D01*
X29241D01*
X28841Y-351600D01*
X29241Y-351200D01*
X28841D01*
X28441Y-350800D01*
X28041Y-351200D01*
X27641D01*
X28041Y-351600D01*
X27641Y-352000D01*
X28041D01*
X28441Y-352400D01*
Y-352000D02*
X28641Y-351800D01*
X28841D01*
X28641Y-351600D01*
X28841Y-351400D01*
X28641D01*
X28441Y-351200D01*
X28241Y-351400D01*
X28041D01*
X28241Y-351600D01*
X28041Y-351800D01*
X28241D01*
X28441Y-352000D01*
X26441Y-140400D02*
X26841Y-140000D01*
X27241D01*
X26841Y-139600D01*
X27241Y-139200D01*
X26841D01*
X26441Y-138800D01*
X26041Y-139200D01*
X25641D01*
X26041Y-139600D01*
X25641Y-140000D01*
X26041D01*
X26441Y-140400D01*
Y-140000D02*
X26641Y-139800D01*
X26841D01*
X26641Y-139600D01*
X26841Y-139400D01*
X26641D01*
X26441Y-139200D01*
X26241Y-139400D01*
X26041D01*
X26241Y-139600D01*
X26041Y-139800D01*
X26241D01*
X26441Y-140000D01*
X24441Y-144400D02*
X24841Y-144000D01*
X25241D01*
X24841Y-143600D01*
X25241Y-143200D01*
X24841D01*
X24441Y-142800D01*
X24041Y-143200D01*
X23641D01*
X24041Y-143600D01*
X23641Y-144000D01*
X24041D01*
X24441Y-144400D01*
Y-144000D02*
X24641Y-143800D01*
X24841D01*
X24641Y-143600D01*
X24841Y-143400D01*
X24641D01*
X24441Y-143200D01*
X24241Y-143400D01*
X24041D01*
X24241Y-143600D01*
X24041Y-143800D01*
X24241D01*
X24441Y-144000D01*
X26441Y-148400D02*
X26841Y-148000D01*
X27241D01*
X26841Y-147600D01*
X27241Y-147200D01*
X26841D01*
X26441Y-146800D01*
X26041Y-147200D01*
X25641D01*
X26041Y-147600D01*
X25641Y-148000D01*
X26041D01*
X26441Y-148400D01*
Y-148000D02*
X26641Y-147800D01*
X26841D01*
X26641Y-147600D01*
X26841Y-147400D01*
X26641D01*
X26441Y-147200D01*
X26241Y-147400D01*
X26041D01*
X26241Y-147600D01*
X26041Y-147800D01*
X26241D01*
X26441Y-148000D01*
X24441Y-152400D02*
X24841Y-152000D01*
X25241D01*
X24841Y-151600D01*
X25241Y-151200D01*
X24841D01*
X24441Y-150800D01*
X24041Y-151200D01*
X23641D01*
X24041Y-151600D01*
X23641Y-152000D01*
X24041D01*
X24441Y-152400D01*
Y-152000D02*
X24641Y-151800D01*
X24841D01*
X24641Y-151600D01*
X24841Y-151400D01*
X24641D01*
X24441Y-151200D01*
X24241Y-151400D01*
X24041D01*
X24241Y-151600D01*
X24041Y-151800D01*
X24241D01*
X24441Y-152000D01*
X26441Y-164400D02*
X26841Y-164000D01*
X27241D01*
X26841Y-163600D01*
X27241Y-163200D01*
X26841D01*
X26441Y-162800D01*
X26041Y-163200D01*
X25641D01*
X26041Y-163600D01*
X25641Y-164000D01*
X26041D01*
X26441Y-164400D01*
Y-164000D02*
X26641Y-163800D01*
X26841D01*
X26641Y-163600D01*
X26841Y-163400D01*
X26641D01*
X26441Y-163200D01*
X26241Y-163400D01*
X26041D01*
X26241Y-163600D01*
X26041Y-163800D01*
X26241D01*
X26441Y-164000D01*
X24441Y-168400D02*
X24841Y-168000D01*
X25241D01*
X24841Y-167600D01*
X25241Y-167200D01*
X24841D01*
X24441Y-166800D01*
X24041Y-167200D01*
X23641D01*
X24041Y-167600D01*
X23641Y-168000D01*
X24041D01*
X24441Y-168400D01*
Y-168000D02*
X24641Y-167800D01*
X24841D01*
X24641Y-167600D01*
X24841Y-167400D01*
X24641D01*
X24441Y-167200D01*
X24241Y-167400D01*
X24041D01*
X24241Y-167600D01*
X24041Y-167800D01*
X24241D01*
X24441Y-168000D01*
Y-192400D02*
X24841Y-192000D01*
X25241D01*
X24841Y-191600D01*
X25241Y-191200D01*
X24841D01*
X24441Y-190800D01*
X24041Y-191200D01*
X23641D01*
X24041Y-191600D01*
X23641Y-192000D01*
X24041D01*
X24441Y-192400D01*
Y-192000D02*
X24641Y-191800D01*
X24841D01*
X24641Y-191600D01*
X24841Y-191400D01*
X24641D01*
X24441Y-191200D01*
X24241Y-191400D01*
X24041D01*
X24241Y-191600D01*
X24041Y-191800D01*
X24241D01*
X24441Y-192000D01*
X26441Y-196400D02*
X26841Y-196000D01*
X27241D01*
X26841Y-195600D01*
X27241Y-195200D01*
X26841D01*
X26441Y-194800D01*
X26041Y-195200D01*
X25641D01*
X26041Y-195600D01*
X25641Y-196000D01*
X26041D01*
X26441Y-196400D01*
Y-196000D02*
X26641Y-195800D01*
X26841D01*
X26641Y-195600D01*
X26841Y-195400D01*
X26641D01*
X26441Y-195200D01*
X26241Y-195400D01*
X26041D01*
X26241Y-195600D01*
X26041Y-195800D01*
X26241D01*
X26441Y-196000D01*
X24441Y-288400D02*
X24841Y-288000D01*
X25241D01*
X24841Y-287600D01*
X25241Y-287200D01*
X24841D01*
X24441Y-286800D01*
X24041Y-287200D01*
X23641D01*
X24041Y-287600D01*
X23641Y-288000D01*
X24041D01*
X24441Y-288400D01*
Y-288000D02*
X24641Y-287800D01*
X24841D01*
X24641Y-287600D01*
X24841Y-287400D01*
X24641D01*
X24441Y-287200D01*
X24241Y-287400D01*
X24041D01*
X24241Y-287600D01*
X24041Y-287800D01*
X24241D01*
X24441Y-288000D01*
X26441Y-300400D02*
X26841Y-300000D01*
X27241D01*
X26841Y-299600D01*
X27241Y-299200D01*
X26841D01*
X26441Y-298800D01*
X26041Y-299200D01*
X25641D01*
X26041Y-299600D01*
X25641Y-300000D01*
X26041D01*
X26441Y-300400D01*
Y-300000D02*
X26641Y-299800D01*
X26841D01*
X26641Y-299600D01*
X26841Y-299400D01*
X26641D01*
X26441Y-299200D01*
X26241Y-299400D01*
X26041D01*
X26241Y-299600D01*
X26041Y-299800D01*
X26241D01*
X26441Y-300000D01*
X24441Y-304400D02*
X24841Y-304000D01*
X25241D01*
X24841Y-303600D01*
X25241Y-303200D01*
X24841D01*
X24441Y-302800D01*
X24041Y-303200D01*
X23641D01*
X24041Y-303600D01*
X23641Y-304000D01*
X24041D01*
X24441Y-304400D01*
Y-304000D02*
X24641Y-303800D01*
X24841D01*
X24641Y-303600D01*
X24841Y-303400D01*
X24641D01*
X24441Y-303200D01*
X24241Y-303400D01*
X24041D01*
X24241Y-303600D01*
X24041Y-303800D01*
X24241D01*
X24441Y-304000D01*
X26441Y-308400D02*
X26841Y-308000D01*
X27241D01*
X26841Y-307600D01*
X27241Y-307200D01*
X26841D01*
X26441Y-306800D01*
X26041Y-307200D01*
X25641D01*
X26041Y-307600D01*
X25641Y-308000D01*
X26041D01*
X26441Y-308400D01*
Y-308000D02*
X26641Y-307800D01*
X26841D01*
X26641Y-307600D01*
X26841Y-307400D01*
X26641D01*
X26441Y-307200D01*
X26241Y-307400D01*
X26041D01*
X26241Y-307600D01*
X26041Y-307800D01*
X26241D01*
X26441Y-308000D01*
X24441Y-312400D02*
X24841Y-312000D01*
X25241D01*
X24841Y-311600D01*
X25241Y-311200D01*
X24841D01*
X24441Y-310800D01*
X24041Y-311200D01*
X23641D01*
X24041Y-311600D01*
X23641Y-312000D01*
X24041D01*
X24441Y-312400D01*
Y-312000D02*
X24641Y-311800D01*
X24841D01*
X24641Y-311600D01*
X24841Y-311400D01*
X24641D01*
X24441Y-311200D01*
X24241Y-311400D01*
X24041D01*
X24241Y-311600D01*
X24041Y-311800D01*
X24241D01*
X24441Y-312000D01*
X26441Y-332400D02*
X26841Y-332000D01*
X27241D01*
X26841Y-331600D01*
X27241Y-331200D01*
X26841D01*
X26441Y-330800D01*
X26041Y-331200D01*
X25641D01*
X26041Y-331600D01*
X25641Y-332000D01*
X26041D01*
X26441Y-332400D01*
Y-332000D02*
X26641Y-331800D01*
X26841D01*
X26641Y-331600D01*
X26841Y-331400D01*
X26641D01*
X26441Y-331200D01*
X26241Y-331400D01*
X26041D01*
X26241Y-331600D01*
X26041Y-331800D01*
X26241D01*
X26441Y-332000D01*
X24441Y-336400D02*
X24841Y-336000D01*
X25241D01*
X24841Y-335600D01*
X25241Y-335200D01*
X24841D01*
X24441Y-334800D01*
X24041Y-335200D01*
X23641D01*
X24041Y-335600D01*
X23641Y-336000D01*
X24041D01*
X24441Y-336400D01*
Y-336000D02*
X24641Y-335800D01*
X24841D01*
X24641Y-335600D01*
X24841Y-335400D01*
X24641D01*
X24441Y-335200D01*
X24241Y-335400D01*
X24041D01*
X24241Y-335600D01*
X24041Y-335800D01*
X24241D01*
X24441Y-336000D01*
X26441Y-340400D02*
X26841Y-340000D01*
X27241D01*
X26841Y-339600D01*
X27241Y-339200D01*
X26841D01*
X26441Y-338800D01*
X26041Y-339200D01*
X25641D01*
X26041Y-339600D01*
X25641Y-340000D01*
X26041D01*
X26441Y-340400D01*
Y-340000D02*
X26641Y-339800D01*
X26841D01*
X26641Y-339600D01*
X26841Y-339400D01*
X26641D01*
X26441Y-339200D01*
X26241Y-339400D01*
X26041D01*
X26241Y-339600D01*
X26041Y-339800D01*
X26241D01*
X26441Y-340000D01*
X24441Y-344400D02*
X24841Y-344000D01*
X25241D01*
X24841Y-343600D01*
X25241Y-343200D01*
X24841D01*
X24441Y-342800D01*
X24041Y-343200D01*
X23641D01*
X24041Y-343600D01*
X23641Y-344000D01*
X24041D01*
X24441Y-344400D01*
Y-344000D02*
X24641Y-343800D01*
X24841D01*
X24641Y-343600D01*
X24841Y-343400D01*
X24641D01*
X24441Y-343200D01*
X24241Y-343400D01*
X24041D01*
X24241Y-343600D01*
X24041Y-343800D01*
X24241D01*
X24441Y-344000D01*
Y-352400D02*
X24841Y-352000D01*
X25241D01*
X24841Y-351600D01*
X25241Y-351200D01*
X24841D01*
X24441Y-350800D01*
X24041Y-351200D01*
X23641D01*
X24041Y-351600D01*
X23641Y-352000D01*
X24041D01*
X24441Y-352400D01*
Y-352000D02*
X24641Y-351800D01*
X24841D01*
X24641Y-351600D01*
X24841Y-351400D01*
X24641D01*
X24441Y-351200D01*
X24241Y-351400D01*
X24041D01*
X24241Y-351600D01*
X24041Y-351800D01*
X24241D01*
X24441Y-352000D01*
X22441Y-140400D02*
X22841Y-140000D01*
X23241D01*
X22841Y-139600D01*
X23241Y-139200D01*
X22841D01*
X22441Y-138800D01*
X22041Y-139200D01*
X21641D01*
X22041Y-139600D01*
X21641Y-140000D01*
X22041D01*
X22441Y-140400D01*
Y-140000D02*
X22641Y-139800D01*
X22841D01*
X22641Y-139600D01*
X22841Y-139400D01*
X22641D01*
X22441Y-139200D01*
X22241Y-139400D01*
X22041D01*
X22241Y-139600D01*
X22041Y-139800D01*
X22241D01*
X22441Y-140000D01*
X20441Y-144400D02*
X20841Y-144000D01*
X21241D01*
X20841Y-143600D01*
X21241Y-143200D01*
X20841D01*
X20441Y-142800D01*
X20041Y-143200D01*
X19641D01*
X20041Y-143600D01*
X19641Y-144000D01*
X20041D01*
X20441Y-144400D01*
Y-144000D02*
X20641Y-143800D01*
X20841D01*
X20641Y-143600D01*
X20841Y-143400D01*
X20641D01*
X20441Y-143200D01*
X20241Y-143400D01*
X20041D01*
X20241Y-143600D01*
X20041Y-143800D01*
X20241D01*
X20441Y-144000D01*
X22441Y-148400D02*
X22841Y-148000D01*
X23241D01*
X22841Y-147600D01*
X23241Y-147200D01*
X22841D01*
X22441Y-146800D01*
X22041Y-147200D01*
X21641D01*
X22041Y-147600D01*
X21641Y-148000D01*
X22041D01*
X22441Y-148400D01*
Y-148000D02*
X22641Y-147800D01*
X22841D01*
X22641Y-147600D01*
X22841Y-147400D01*
X22641D01*
X22441Y-147200D01*
X22241Y-147400D01*
X22041D01*
X22241Y-147600D01*
X22041Y-147800D01*
X22241D01*
X22441Y-148000D01*
X20441Y-152400D02*
X20841Y-152000D01*
X21241D01*
X20841Y-151600D01*
X21241Y-151200D01*
X20841D01*
X20441Y-150800D01*
X20041Y-151200D01*
X19641D01*
X20041Y-151600D01*
X19641Y-152000D01*
X20041D01*
X20441Y-152400D01*
Y-152000D02*
X20641Y-151800D01*
X20841D01*
X20641Y-151600D01*
X20841Y-151400D01*
X20641D01*
X20441Y-151200D01*
X20241Y-151400D01*
X20041D01*
X20241Y-151600D01*
X20041Y-151800D01*
X20241D01*
X20441Y-152000D01*
X22441Y-164400D02*
X22841Y-164000D01*
X23241D01*
X22841Y-163600D01*
X23241Y-163200D01*
X22841D01*
X22441Y-162800D01*
X22041Y-163200D01*
X21641D01*
X22041Y-163600D01*
X21641Y-164000D01*
X22041D01*
X22441Y-164400D01*
Y-164000D02*
X22641Y-163800D01*
X22841D01*
X22641Y-163600D01*
X22841Y-163400D01*
X22641D01*
X22441Y-163200D01*
X22241Y-163400D01*
X22041D01*
X22241Y-163600D01*
X22041Y-163800D01*
X22241D01*
X22441Y-164000D01*
X20441Y-168400D02*
X20841Y-168000D01*
X21241D01*
X20841Y-167600D01*
X21241Y-167200D01*
X20841D01*
X20441Y-166800D01*
X20041Y-167200D01*
X19641D01*
X20041Y-167600D01*
X19641Y-168000D01*
X20041D01*
X20441Y-168400D01*
Y-168000D02*
X20641Y-167800D01*
X20841D01*
X20641Y-167600D01*
X20841Y-167400D01*
X20641D01*
X20441Y-167200D01*
X20241Y-167400D01*
X20041D01*
X20241Y-167600D01*
X20041Y-167800D01*
X20241D01*
X20441Y-168000D01*
X22441Y-172400D02*
X22841Y-172000D01*
X23241D01*
X22841Y-171600D01*
X23241Y-171200D01*
X22841D01*
X22441Y-170800D01*
X22041Y-171200D01*
X21641D01*
X22041Y-171600D01*
X21641Y-172000D01*
X22041D01*
X22441Y-172400D01*
Y-172000D02*
X22641Y-171800D01*
X22841D01*
X22641Y-171600D01*
X22841Y-171400D01*
X22641D01*
X22441Y-171200D01*
X22241Y-171400D01*
X22041D01*
X22241Y-171600D01*
X22041Y-171800D01*
X22241D01*
X22441Y-172000D01*
X20441Y-192400D02*
X20841Y-192000D01*
X21241D01*
X20841Y-191600D01*
X21241Y-191200D01*
X20841D01*
X20441Y-190800D01*
X20041Y-191200D01*
X19641D01*
X20041Y-191600D01*
X19641Y-192000D01*
X20041D01*
X20441Y-192400D01*
Y-192000D02*
X20641Y-191800D01*
X20841D01*
X20641Y-191600D01*
X20841Y-191400D01*
X20641D01*
X20441Y-191200D01*
X20241Y-191400D01*
X20041D01*
X20241Y-191600D01*
X20041Y-191800D01*
X20241D01*
X20441Y-192000D01*
X22441Y-196400D02*
X22841Y-196000D01*
X23241D01*
X22841Y-195600D01*
X23241Y-195200D01*
X22841D01*
X22441Y-194800D01*
X22041Y-195200D01*
X21641D01*
X22041Y-195600D01*
X21641Y-196000D01*
X22041D01*
X22441Y-196400D01*
Y-196000D02*
X22641Y-195800D01*
X22841D01*
X22641Y-195600D01*
X22841Y-195400D01*
X22641D01*
X22441Y-195200D01*
X22241Y-195400D01*
X22041D01*
X22241Y-195600D01*
X22041Y-195800D01*
X22241D01*
X22441Y-196000D01*
X20441Y-200400D02*
X20841Y-200000D01*
X21241D01*
X20841Y-199600D01*
X21241Y-199200D01*
X20841D01*
X20441Y-198800D01*
X20041Y-199200D01*
X19641D01*
X20041Y-199600D01*
X19641Y-200000D01*
X20041D01*
X20441Y-200400D01*
Y-200000D02*
X20641Y-199800D01*
X20841D01*
X20641Y-199600D01*
X20841Y-199400D01*
X20641D01*
X20441Y-199200D01*
X20241Y-199400D01*
X20041D01*
X20241Y-199600D01*
X20041Y-199800D01*
X20241D01*
X20441Y-200000D01*
Y-232400D02*
X20841Y-232000D01*
X21241D01*
X20841Y-231600D01*
X21241Y-231200D01*
X20841D01*
X20441Y-230800D01*
X20041Y-231200D01*
X19641D01*
X20041Y-231600D01*
X19641Y-232000D01*
X20041D01*
X20441Y-232400D01*
Y-232000D02*
X20641Y-231800D01*
X20841D01*
X20641Y-231600D01*
X20841Y-231400D01*
X20641D01*
X20441Y-231200D01*
X20241Y-231400D01*
X20041D01*
X20241Y-231600D01*
X20041Y-231800D01*
X20241D01*
X20441Y-232000D01*
X22441Y-236400D02*
X22841Y-236000D01*
X23241D01*
X22841Y-235600D01*
X23241Y-235200D01*
X22841D01*
X22441Y-234800D01*
X22041Y-235200D01*
X21641D01*
X22041Y-235600D01*
X21641Y-236000D01*
X22041D01*
X22441Y-236400D01*
Y-236000D02*
X22641Y-235800D01*
X22841D01*
X22641Y-235600D01*
X22841Y-235400D01*
X22641D01*
X22441Y-235200D01*
X22241Y-235400D01*
X22041D01*
X22241Y-235600D01*
X22041Y-235800D01*
X22241D01*
X22441Y-236000D01*
Y-244400D02*
X22841Y-244000D01*
X23241D01*
X22841Y-243600D01*
X23241Y-243200D01*
X22841D01*
X22441Y-242800D01*
X22041Y-243200D01*
X21641D01*
X22041Y-243600D01*
X21641Y-244000D01*
X22041D01*
X22441Y-244400D01*
Y-244000D02*
X22641Y-243800D01*
X22841D01*
X22641Y-243600D01*
X22841Y-243400D01*
X22641D01*
X22441Y-243200D01*
X22241Y-243400D01*
X22041D01*
X22241Y-243600D01*
X22041Y-243800D01*
X22241D01*
X22441Y-244000D01*
X20441Y-248400D02*
X20841Y-248000D01*
X21241D01*
X20841Y-247600D01*
X21241Y-247200D01*
X20841D01*
X20441Y-246800D01*
X20041Y-247200D01*
X19641D01*
X20041Y-247600D01*
X19641Y-248000D01*
X20041D01*
X20441Y-248400D01*
Y-248000D02*
X20641Y-247800D01*
X20841D01*
X20641Y-247600D01*
X20841Y-247400D01*
X20641D01*
X20441Y-247200D01*
X20241Y-247400D01*
X20041D01*
X20241Y-247600D01*
X20041Y-247800D01*
X20241D01*
X20441Y-248000D01*
X22441Y-252400D02*
X22841Y-252000D01*
X23241D01*
X22841Y-251600D01*
X23241Y-251200D01*
X22841D01*
X22441Y-250800D01*
X22041Y-251200D01*
X21641D01*
X22041Y-251600D01*
X21641Y-252000D01*
X22041D01*
X22441Y-252400D01*
Y-252000D02*
X22641Y-251800D01*
X22841D01*
X22641Y-251600D01*
X22841Y-251400D01*
X22641D01*
X22441Y-251200D01*
X22241Y-251400D01*
X22041D01*
X22241Y-251600D01*
X22041Y-251800D01*
X22241D01*
X22441Y-252000D01*
X20441Y-256400D02*
X20841Y-256000D01*
X21241D01*
X20841Y-255600D01*
X21241Y-255200D01*
X20841D01*
X20441Y-254800D01*
X20041Y-255200D01*
X19641D01*
X20041Y-255600D01*
X19641Y-256000D01*
X20041D01*
X20441Y-256400D01*
Y-256000D02*
X20641Y-255800D01*
X20841D01*
X20641Y-255600D01*
X20841Y-255400D01*
X20641D01*
X20441Y-255200D01*
X20241Y-255400D01*
X20041D01*
X20241Y-255600D01*
X20041Y-255800D01*
X20241D01*
X20441Y-256000D01*
X22441Y-260400D02*
X22841Y-260000D01*
X23241D01*
X22841Y-259600D01*
X23241Y-259200D01*
X22841D01*
X22441Y-258800D01*
X22041Y-259200D01*
X21641D01*
X22041Y-259600D01*
X21641Y-260000D01*
X22041D01*
X22441Y-260400D01*
Y-260000D02*
X22641Y-259800D01*
X22841D01*
X22641Y-259600D01*
X22841Y-259400D01*
X22641D01*
X22441Y-259200D01*
X22241Y-259400D01*
X22041D01*
X22241Y-259600D01*
X22041Y-259800D01*
X22241D01*
X22441Y-260000D01*
Y-268400D02*
X22841Y-268000D01*
X23241D01*
X22841Y-267600D01*
X23241Y-267200D01*
X22841D01*
X22441Y-266800D01*
X22041Y-267200D01*
X21641D01*
X22041Y-267600D01*
X21641Y-268000D01*
X22041D01*
X22441Y-268400D01*
Y-268000D02*
X22641Y-267800D01*
X22841D01*
X22641Y-267600D01*
X22841Y-267400D01*
X22641D01*
X22441Y-267200D01*
X22241Y-267400D01*
X22041D01*
X22241Y-267600D01*
X22041Y-267800D01*
X22241D01*
X22441Y-268000D01*
X20441Y-272400D02*
X20841Y-272000D01*
X21241D01*
X20841Y-271600D01*
X21241Y-271200D01*
X20841D01*
X20441Y-270800D01*
X20041Y-271200D01*
X19641D01*
X20041Y-271600D01*
X19641Y-272000D01*
X20041D01*
X20441Y-272400D01*
Y-272000D02*
X20641Y-271800D01*
X20841D01*
X20641Y-271600D01*
X20841Y-271400D01*
X20641D01*
X20441Y-271200D01*
X20241Y-271400D01*
X20041D01*
X20241Y-271600D01*
X20041Y-271800D01*
X20241D01*
X20441Y-272000D01*
X22441Y-284400D02*
X22841Y-284000D01*
X23241D01*
X22841Y-283600D01*
X23241Y-283200D01*
X22841D01*
X22441Y-282800D01*
X22041Y-283200D01*
X21641D01*
X22041Y-283600D01*
X21641Y-284000D01*
X22041D01*
X22441Y-284400D01*
Y-284000D02*
X22641Y-283800D01*
X22841D01*
X22641Y-283600D01*
X22841Y-283400D01*
X22641D01*
X22441Y-283200D01*
X22241Y-283400D01*
X22041D01*
X22241Y-283600D01*
X22041Y-283800D01*
X22241D01*
X22441Y-284000D01*
X20441Y-288400D02*
X20841Y-288000D01*
X21241D01*
X20841Y-287600D01*
X21241Y-287200D01*
X20841D01*
X20441Y-286800D01*
X20041Y-287200D01*
X19641D01*
X20041Y-287600D01*
X19641Y-288000D01*
X20041D01*
X20441Y-288400D01*
Y-288000D02*
X20641Y-287800D01*
X20841D01*
X20641Y-287600D01*
X20841Y-287400D01*
X20641D01*
X20441Y-287200D01*
X20241Y-287400D01*
X20041D01*
X20241Y-287600D01*
X20041Y-287800D01*
X20241D01*
X20441Y-288000D01*
X22441Y-292400D02*
X22841Y-292000D01*
X23241D01*
X22841Y-291600D01*
X23241Y-291200D01*
X22841D01*
X22441Y-290800D01*
X22041Y-291200D01*
X21641D01*
X22041Y-291600D01*
X21641Y-292000D01*
X22041D01*
X22441Y-292400D01*
Y-292000D02*
X22641Y-291800D01*
X22841D01*
X22641Y-291600D01*
X22841Y-291400D01*
X22641D01*
X22441Y-291200D01*
X22241Y-291400D01*
X22041D01*
X22241Y-291600D01*
X22041Y-291800D01*
X22241D01*
X22441Y-292000D01*
Y-300400D02*
X22841Y-300000D01*
X23241D01*
X22841Y-299600D01*
X23241Y-299200D01*
X22841D01*
X22441Y-298800D01*
X22041Y-299200D01*
X21641D01*
X22041Y-299600D01*
X21641Y-300000D01*
X22041D01*
X22441Y-300400D01*
Y-300000D02*
X22641Y-299800D01*
X22841D01*
X22641Y-299600D01*
X22841Y-299400D01*
X22641D01*
X22441Y-299200D01*
X22241Y-299400D01*
X22041D01*
X22241Y-299600D01*
X22041Y-299800D01*
X22241D01*
X22441Y-300000D01*
X20441Y-304400D02*
X20841Y-304000D01*
X21241D01*
X20841Y-303600D01*
X21241Y-303200D01*
X20841D01*
X20441Y-302800D01*
X20041Y-303200D01*
X19641D01*
X20041Y-303600D01*
X19641Y-304000D01*
X20041D01*
X20441Y-304400D01*
Y-304000D02*
X20641Y-303800D01*
X20841D01*
X20641Y-303600D01*
X20841Y-303400D01*
X20641D01*
X20441Y-303200D01*
X20241Y-303400D01*
X20041D01*
X20241Y-303600D01*
X20041Y-303800D01*
X20241D01*
X20441Y-304000D01*
X22441Y-308400D02*
X22841Y-308000D01*
X23241D01*
X22841Y-307600D01*
X23241Y-307200D01*
X22841D01*
X22441Y-306800D01*
X22041Y-307200D01*
X21641D01*
X22041Y-307600D01*
X21641Y-308000D01*
X22041D01*
X22441Y-308400D01*
Y-308000D02*
X22641Y-307800D01*
X22841D01*
X22641Y-307600D01*
X22841Y-307400D01*
X22641D01*
X22441Y-307200D01*
X22241Y-307400D01*
X22041D01*
X22241Y-307600D01*
X22041Y-307800D01*
X22241D01*
X22441Y-308000D01*
X20441Y-312400D02*
X20841Y-312000D01*
X21241D01*
X20841Y-311600D01*
X21241Y-311200D01*
X20841D01*
X20441Y-310800D01*
X20041Y-311200D01*
X19641D01*
X20041Y-311600D01*
X19641Y-312000D01*
X20041D01*
X20441Y-312400D01*
Y-312000D02*
X20641Y-311800D01*
X20841D01*
X20641Y-311600D01*
X20841Y-311400D01*
X20641D01*
X20441Y-311200D01*
X20241Y-311400D01*
X20041D01*
X20241Y-311600D01*
X20041Y-311800D01*
X20241D01*
X20441Y-312000D01*
X22441Y-324400D02*
X22841Y-324000D01*
X23241D01*
X22841Y-323600D01*
X23241Y-323200D01*
X22841D01*
X22441Y-322800D01*
X22041Y-323200D01*
X21641D01*
X22041Y-323600D01*
X21641Y-324000D01*
X22041D01*
X22441Y-324400D01*
Y-324000D02*
X22641Y-323800D01*
X22841D01*
X22641Y-323600D01*
X22841Y-323400D01*
X22641D01*
X22441Y-323200D01*
X22241Y-323400D01*
X22041D01*
X22241Y-323600D01*
X22041Y-323800D01*
X22241D01*
X22441Y-324000D01*
X20441Y-336400D02*
X20841Y-336000D01*
X21241D01*
X20841Y-335600D01*
X21241Y-335200D01*
X20841D01*
X20441Y-334800D01*
X20041Y-335200D01*
X19641D01*
X20041Y-335600D01*
X19641Y-336000D01*
X20041D01*
X20441Y-336400D01*
Y-336000D02*
X20641Y-335800D01*
X20841D01*
X20641Y-335600D01*
X20841Y-335400D01*
X20641D01*
X20441Y-335200D01*
X20241Y-335400D01*
X20041D01*
X20241Y-335600D01*
X20041Y-335800D01*
X20241D01*
X20441Y-336000D01*
X22441Y-340400D02*
X22841Y-340000D01*
X23241D01*
X22841Y-339600D01*
X23241Y-339200D01*
X22841D01*
X22441Y-338800D01*
X22041Y-339200D01*
X21641D01*
X22041Y-339600D01*
X21641Y-340000D01*
X22041D01*
X22441Y-340400D01*
Y-340000D02*
X22641Y-339800D01*
X22841D01*
X22641Y-339600D01*
X22841Y-339400D01*
X22641D01*
X22441Y-339200D01*
X22241Y-339400D01*
X22041D01*
X22241Y-339600D01*
X22041Y-339800D01*
X22241D01*
X22441Y-340000D01*
X20441Y-344400D02*
X20841Y-344000D01*
X21241D01*
X20841Y-343600D01*
X21241Y-343200D01*
X20841D01*
X20441Y-342800D01*
X20041Y-343200D01*
X19641D01*
X20041Y-343600D01*
X19641Y-344000D01*
X20041D01*
X20441Y-344400D01*
Y-344000D02*
X20641Y-343800D01*
X20841D01*
X20641Y-343600D01*
X20841Y-343400D01*
X20641D01*
X20441Y-343200D01*
X20241Y-343400D01*
X20041D01*
X20241Y-343600D01*
X20041Y-343800D01*
X20241D01*
X20441Y-344000D01*
Y-352400D02*
X20841Y-352000D01*
X21241D01*
X20841Y-351600D01*
X21241Y-351200D01*
X20841D01*
X20441Y-350800D01*
X20041Y-351200D01*
X19641D01*
X20041Y-351600D01*
X19641Y-352000D01*
X20041D01*
X20441Y-352400D01*
Y-352000D02*
X20641Y-351800D01*
X20841D01*
X20641Y-351600D01*
X20841Y-351400D01*
X20641D01*
X20441Y-351200D01*
X20241Y-351400D01*
X20041D01*
X20241Y-351600D01*
X20041Y-351800D01*
X20241D01*
X20441Y-352000D01*
X18441Y-140400D02*
X18841Y-140000D01*
X19241D01*
X18841Y-139600D01*
X19241Y-139200D01*
X18841D01*
X18441Y-138800D01*
X18041Y-139200D01*
X17641D01*
X18041Y-139600D01*
X17641Y-140000D01*
X18041D01*
X18441Y-140400D01*
Y-140000D02*
X18641Y-139800D01*
X18841D01*
X18641Y-139600D01*
X18841Y-139400D01*
X18641D01*
X18441Y-139200D01*
X18241Y-139400D01*
X18041D01*
X18241Y-139600D01*
X18041Y-139800D01*
X18241D01*
X18441Y-140000D01*
X16441Y-144400D02*
X16841Y-144000D01*
X17241D01*
X16841Y-143600D01*
X17241Y-143200D01*
X16841D01*
X16441Y-142800D01*
X16041Y-143200D01*
X15641D01*
X16041Y-143600D01*
X15641Y-144000D01*
X16041D01*
X16441Y-144400D01*
Y-144000D02*
X16641Y-143800D01*
X16841D01*
X16641Y-143600D01*
X16841Y-143400D01*
X16641D01*
X16441Y-143200D01*
X16241Y-143400D01*
X16041D01*
X16241Y-143600D01*
X16041Y-143800D01*
X16241D01*
X16441Y-144000D01*
X18441Y-148400D02*
X18841Y-148000D01*
X19241D01*
X18841Y-147600D01*
X19241Y-147200D01*
X18841D01*
X18441Y-146800D01*
X18041Y-147200D01*
X17641D01*
X18041Y-147600D01*
X17641Y-148000D01*
X18041D01*
X18441Y-148400D01*
Y-148000D02*
X18641Y-147800D01*
X18841D01*
X18641Y-147600D01*
X18841Y-147400D01*
X18641D01*
X18441Y-147200D01*
X18241Y-147400D01*
X18041D01*
X18241Y-147600D01*
X18041Y-147800D01*
X18241D01*
X18441Y-148000D01*
X16441Y-152400D02*
X16841Y-152000D01*
X17241D01*
X16841Y-151600D01*
X17241Y-151200D01*
X16841D01*
X16441Y-150800D01*
X16041Y-151200D01*
X15641D01*
X16041Y-151600D01*
X15641Y-152000D01*
X16041D01*
X16441Y-152400D01*
Y-152000D02*
X16641Y-151800D01*
X16841D01*
X16641Y-151600D01*
X16841Y-151400D01*
X16641D01*
X16441Y-151200D01*
X16241Y-151400D01*
X16041D01*
X16241Y-151600D01*
X16041Y-151800D01*
X16241D01*
X16441Y-152000D01*
X18441Y-164400D02*
X18841Y-164000D01*
X19241D01*
X18841Y-163600D01*
X19241Y-163200D01*
X18841D01*
X18441Y-162800D01*
X18041Y-163200D01*
X17641D01*
X18041Y-163600D01*
X17641Y-164000D01*
X18041D01*
X18441Y-164400D01*
Y-164000D02*
X18641Y-163800D01*
X18841D01*
X18641Y-163600D01*
X18841Y-163400D01*
X18641D01*
X18441Y-163200D01*
X18241Y-163400D01*
X18041D01*
X18241Y-163600D01*
X18041Y-163800D01*
X18241D01*
X18441Y-164000D01*
X16441Y-168400D02*
X16841Y-168000D01*
X17241D01*
X16841Y-167600D01*
X17241Y-167200D01*
X16841D01*
X16441Y-166800D01*
X16041Y-167200D01*
X15641D01*
X16041Y-167600D01*
X15641Y-168000D01*
X16041D01*
X16441Y-168400D01*
Y-168000D02*
X16641Y-167800D01*
X16841D01*
X16641Y-167600D01*
X16841Y-167400D01*
X16641D01*
X16441Y-167200D01*
X16241Y-167400D01*
X16041D01*
X16241Y-167600D01*
X16041Y-167800D01*
X16241D01*
X16441Y-168000D01*
X18441Y-172400D02*
X18841Y-172000D01*
X19241D01*
X18841Y-171600D01*
X19241Y-171200D01*
X18841D01*
X18441Y-170800D01*
X18041Y-171200D01*
X17641D01*
X18041Y-171600D01*
X17641Y-172000D01*
X18041D01*
X18441Y-172400D01*
Y-172000D02*
X18641Y-171800D01*
X18841D01*
X18641Y-171600D01*
X18841Y-171400D01*
X18641D01*
X18441Y-171200D01*
X18241Y-171400D01*
X18041D01*
X18241Y-171600D01*
X18041Y-171800D01*
X18241D01*
X18441Y-172000D01*
X16441Y-192400D02*
X16841Y-192000D01*
X17241D01*
X16841Y-191600D01*
X17241Y-191200D01*
X16841D01*
X16441Y-190800D01*
X16041Y-191200D01*
X15641D01*
X16041Y-191600D01*
X15641Y-192000D01*
X16041D01*
X16441Y-192400D01*
Y-192000D02*
X16641Y-191800D01*
X16841D01*
X16641Y-191600D01*
X16841Y-191400D01*
X16641D01*
X16441Y-191200D01*
X16241Y-191400D01*
X16041D01*
X16241Y-191600D01*
X16041Y-191800D01*
X16241D01*
X16441Y-192000D01*
X18441Y-196400D02*
X18841Y-196000D01*
X19241D01*
X18841Y-195600D01*
X19241Y-195200D01*
X18841D01*
X18441Y-194800D01*
X18041Y-195200D01*
X17641D01*
X18041Y-195600D01*
X17641Y-196000D01*
X18041D01*
X18441Y-196400D01*
Y-196000D02*
X18641Y-195800D01*
X18841D01*
X18641Y-195600D01*
X18841Y-195400D01*
X18641D01*
X18441Y-195200D01*
X18241Y-195400D01*
X18041D01*
X18241Y-195600D01*
X18041Y-195800D01*
X18241D01*
X18441Y-196000D01*
X16441Y-200400D02*
X16841Y-200000D01*
X17241D01*
X16841Y-199600D01*
X17241Y-199200D01*
X16841D01*
X16441Y-198800D01*
X16041Y-199200D01*
X15641D01*
X16041Y-199600D01*
X15641Y-200000D01*
X16041D01*
X16441Y-200400D01*
Y-200000D02*
X16641Y-199800D01*
X16841D01*
X16641Y-199600D01*
X16841Y-199400D01*
X16641D01*
X16441Y-199200D01*
X16241Y-199400D01*
X16041D01*
X16241Y-199600D01*
X16041Y-199800D01*
X16241D01*
X16441Y-200000D01*
X18441Y-204400D02*
X18841Y-204000D01*
X19241D01*
X18841Y-203600D01*
X19241Y-203200D01*
X18841D01*
X18441Y-202800D01*
X18041Y-203200D01*
X17641D01*
X18041Y-203600D01*
X17641Y-204000D01*
X18041D01*
X18441Y-204400D01*
Y-204000D02*
X18641Y-203800D01*
X18841D01*
X18641Y-203600D01*
X18841Y-203400D01*
X18641D01*
X18441Y-203200D01*
X18241Y-203400D01*
X18041D01*
X18241Y-203600D01*
X18041Y-203800D01*
X18241D01*
X18441Y-204000D01*
X16441Y-216400D02*
X16841Y-216000D01*
X17241D01*
X16841Y-215600D01*
X17241Y-215200D01*
X16841D01*
X16441Y-214800D01*
X16041Y-215200D01*
X15641D01*
X16041Y-215600D01*
X15641Y-216000D01*
X16041D01*
X16441Y-216400D01*
Y-216000D02*
X16641Y-215800D01*
X16841D01*
X16641Y-215600D01*
X16841Y-215400D01*
X16641D01*
X16441Y-215200D01*
X16241Y-215400D01*
X16041D01*
X16241Y-215600D01*
X16041Y-215800D01*
X16241D01*
X16441Y-216000D01*
X18441Y-220400D02*
X18841Y-220000D01*
X19241D01*
X18841Y-219600D01*
X19241Y-219200D01*
X18841D01*
X18441Y-218800D01*
X18041Y-219200D01*
X17641D01*
X18041Y-219600D01*
X17641Y-220000D01*
X18041D01*
X18441Y-220400D01*
Y-220000D02*
X18641Y-219800D01*
X18841D01*
X18641Y-219600D01*
X18841Y-219400D01*
X18641D01*
X18441Y-219200D01*
X18241Y-219400D01*
X18041D01*
X18241Y-219600D01*
X18041Y-219800D01*
X18241D01*
X18441Y-220000D01*
X16441Y-224400D02*
X16841Y-224000D01*
X17241D01*
X16841Y-223600D01*
X17241Y-223200D01*
X16841D01*
X16441Y-222800D01*
X16041Y-223200D01*
X15641D01*
X16041Y-223600D01*
X15641Y-224000D01*
X16041D01*
X16441Y-224400D01*
Y-224000D02*
X16641Y-223800D01*
X16841D01*
X16641Y-223600D01*
X16841Y-223400D01*
X16641D01*
X16441Y-223200D01*
X16241Y-223400D01*
X16041D01*
X16241Y-223600D01*
X16041Y-223800D01*
X16241D01*
X16441Y-224000D01*
X18441Y-236400D02*
X18841Y-236000D01*
X19241D01*
X18841Y-235600D01*
X19241Y-235200D01*
X18841D01*
X18441Y-234800D01*
X18041Y-235200D01*
X17641D01*
X18041Y-235600D01*
X17641Y-236000D01*
X18041D01*
X18441Y-236400D01*
Y-236000D02*
X18641Y-235800D01*
X18841D01*
X18641Y-235600D01*
X18841Y-235400D01*
X18641D01*
X18441Y-235200D01*
X18241Y-235400D01*
X18041D01*
X18241Y-235600D01*
X18041Y-235800D01*
X18241D01*
X18441Y-236000D01*
Y-244400D02*
X18841Y-244000D01*
X19241D01*
X18841Y-243600D01*
X19241Y-243200D01*
X18841D01*
X18441Y-242800D01*
X18041Y-243200D01*
X17641D01*
X18041Y-243600D01*
X17641Y-244000D01*
X18041D01*
X18441Y-244400D01*
Y-244000D02*
X18641Y-243800D01*
X18841D01*
X18641Y-243600D01*
X18841Y-243400D01*
X18641D01*
X18441Y-243200D01*
X18241Y-243400D01*
X18041D01*
X18241Y-243600D01*
X18041Y-243800D01*
X18241D01*
X18441Y-244000D01*
X16441Y-248400D02*
X16841Y-248000D01*
X17241D01*
X16841Y-247600D01*
X17241Y-247200D01*
X16841D01*
X16441Y-246800D01*
X16041Y-247200D01*
X15641D01*
X16041Y-247600D01*
X15641Y-248000D01*
X16041D01*
X16441Y-248400D01*
Y-248000D02*
X16641Y-247800D01*
X16841D01*
X16641Y-247600D01*
X16841Y-247400D01*
X16641D01*
X16441Y-247200D01*
X16241Y-247400D01*
X16041D01*
X16241Y-247600D01*
X16041Y-247800D01*
X16241D01*
X16441Y-248000D01*
X18441Y-252400D02*
X18841Y-252000D01*
X19241D01*
X18841Y-251600D01*
X19241Y-251200D01*
X18841D01*
X18441Y-250800D01*
X18041Y-251200D01*
X17641D01*
X18041Y-251600D01*
X17641Y-252000D01*
X18041D01*
X18441Y-252400D01*
Y-252000D02*
X18641Y-251800D01*
X18841D01*
X18641Y-251600D01*
X18841Y-251400D01*
X18641D01*
X18441Y-251200D01*
X18241Y-251400D01*
X18041D01*
X18241Y-251600D01*
X18041Y-251800D01*
X18241D01*
X18441Y-252000D01*
X16441Y-256400D02*
X16841Y-256000D01*
X17241D01*
X16841Y-255600D01*
X17241Y-255200D01*
X16841D01*
X16441Y-254800D01*
X16041Y-255200D01*
X15641D01*
X16041Y-255600D01*
X15641Y-256000D01*
X16041D01*
X16441Y-256400D01*
Y-256000D02*
X16641Y-255800D01*
X16841D01*
X16641Y-255600D01*
X16841Y-255400D01*
X16641D01*
X16441Y-255200D01*
X16241Y-255400D01*
X16041D01*
X16241Y-255600D01*
X16041Y-255800D01*
X16241D01*
X16441Y-256000D01*
X18441Y-260400D02*
X18841Y-260000D01*
X19241D01*
X18841Y-259600D01*
X19241Y-259200D01*
X18841D01*
X18441Y-258800D01*
X18041Y-259200D01*
X17641D01*
X18041Y-259600D01*
X17641Y-260000D01*
X18041D01*
X18441Y-260400D01*
Y-260000D02*
X18641Y-259800D01*
X18841D01*
X18641Y-259600D01*
X18841Y-259400D01*
X18641D01*
X18441Y-259200D01*
X18241Y-259400D01*
X18041D01*
X18241Y-259600D01*
X18041Y-259800D01*
X18241D01*
X18441Y-260000D01*
Y-268400D02*
X18841Y-268000D01*
X19241D01*
X18841Y-267600D01*
X19241Y-267200D01*
X18841D01*
X18441Y-266800D01*
X18041Y-267200D01*
X17641D01*
X18041Y-267600D01*
X17641Y-268000D01*
X18041D01*
X18441Y-268400D01*
Y-268000D02*
X18641Y-267800D01*
X18841D01*
X18641Y-267600D01*
X18841Y-267400D01*
X18641D01*
X18441Y-267200D01*
X18241Y-267400D01*
X18041D01*
X18241Y-267600D01*
X18041Y-267800D01*
X18241D01*
X18441Y-268000D01*
X16441Y-272400D02*
X16841Y-272000D01*
X17241D01*
X16841Y-271600D01*
X17241Y-271200D01*
X16841D01*
X16441Y-270800D01*
X16041Y-271200D01*
X15641D01*
X16041Y-271600D01*
X15641Y-272000D01*
X16041D01*
X16441Y-272400D01*
Y-272000D02*
X16641Y-271800D01*
X16841D01*
X16641Y-271600D01*
X16841Y-271400D01*
X16641D01*
X16441Y-271200D01*
X16241Y-271400D01*
X16041D01*
X16241Y-271600D01*
X16041Y-271800D01*
X16241D01*
X16441Y-272000D01*
X18441Y-276400D02*
X18841Y-276000D01*
X19241D01*
X18841Y-275600D01*
X19241Y-275200D01*
X18841D01*
X18441Y-274800D01*
X18041Y-275200D01*
X17641D01*
X18041Y-275600D01*
X17641Y-276000D01*
X18041D01*
X18441Y-276400D01*
Y-276000D02*
X18641Y-275800D01*
X18841D01*
X18641Y-275600D01*
X18841Y-275400D01*
X18641D01*
X18441Y-275200D01*
X18241Y-275400D01*
X18041D01*
X18241Y-275600D01*
X18041Y-275800D01*
X18241D01*
X18441Y-276000D01*
X16441Y-280400D02*
X16841Y-280000D01*
X17241D01*
X16841Y-279600D01*
X17241Y-279200D01*
X16841D01*
X16441Y-278800D01*
X16041Y-279200D01*
X15641D01*
X16041Y-279600D01*
X15641Y-280000D01*
X16041D01*
X16441Y-280400D01*
Y-280000D02*
X16641Y-279800D01*
X16841D01*
X16641Y-279600D01*
X16841Y-279400D01*
X16641D01*
X16441Y-279200D01*
X16241Y-279400D01*
X16041D01*
X16241Y-279600D01*
X16041Y-279800D01*
X16241D01*
X16441Y-280000D01*
X18441Y-292400D02*
X18841Y-292000D01*
X19241D01*
X18841Y-291600D01*
X19241Y-291200D01*
X18841D01*
X18441Y-290800D01*
X18041Y-291200D01*
X17641D01*
X18041Y-291600D01*
X17641Y-292000D01*
X18041D01*
X18441Y-292400D01*
Y-292000D02*
X18641Y-291800D01*
X18841D01*
X18641Y-291600D01*
X18841Y-291400D01*
X18641D01*
X18441Y-291200D01*
X18241Y-291400D01*
X18041D01*
X18241Y-291600D01*
X18041Y-291800D01*
X18241D01*
X18441Y-292000D01*
Y-300400D02*
X18841Y-300000D01*
X19241D01*
X18841Y-299600D01*
X19241Y-299200D01*
X18841D01*
X18441Y-298800D01*
X18041Y-299200D01*
X17641D01*
X18041Y-299600D01*
X17641Y-300000D01*
X18041D01*
X18441Y-300400D01*
Y-300000D02*
X18641Y-299800D01*
X18841D01*
X18641Y-299600D01*
X18841Y-299400D01*
X18641D01*
X18441Y-299200D01*
X18241Y-299400D01*
X18041D01*
X18241Y-299600D01*
X18041Y-299800D01*
X18241D01*
X18441Y-300000D01*
X16441Y-304400D02*
X16841Y-304000D01*
X17241D01*
X16841Y-303600D01*
X17241Y-303200D01*
X16841D01*
X16441Y-302800D01*
X16041Y-303200D01*
X15641D01*
X16041Y-303600D01*
X15641Y-304000D01*
X16041D01*
X16441Y-304400D01*
Y-304000D02*
X16641Y-303800D01*
X16841D01*
X16641Y-303600D01*
X16841Y-303400D01*
X16641D01*
X16441Y-303200D01*
X16241Y-303400D01*
X16041D01*
X16241Y-303600D01*
X16041Y-303800D01*
X16241D01*
X16441Y-304000D01*
X18441Y-308400D02*
X18841Y-308000D01*
X19241D01*
X18841Y-307600D01*
X19241Y-307200D01*
X18841D01*
X18441Y-306800D01*
X18041Y-307200D01*
X17641D01*
X18041Y-307600D01*
X17641Y-308000D01*
X18041D01*
X18441Y-308400D01*
Y-308000D02*
X18641Y-307800D01*
X18841D01*
X18641Y-307600D01*
X18841Y-307400D01*
X18641D01*
X18441Y-307200D01*
X18241Y-307400D01*
X18041D01*
X18241Y-307600D01*
X18041Y-307800D01*
X18241D01*
X18441Y-308000D01*
X16441Y-312400D02*
X16841Y-312000D01*
X17241D01*
X16841Y-311600D01*
X17241Y-311200D01*
X16841D01*
X16441Y-310800D01*
X16041Y-311200D01*
X15641D01*
X16041Y-311600D01*
X15641Y-312000D01*
X16041D01*
X16441Y-312400D01*
Y-312000D02*
X16641Y-311800D01*
X16841D01*
X16641Y-311600D01*
X16841Y-311400D01*
X16641D01*
X16441Y-311200D01*
X16241Y-311400D01*
X16041D01*
X16241Y-311600D01*
X16041Y-311800D01*
X16241D01*
X16441Y-312000D01*
X18441Y-324400D02*
X18841Y-324000D01*
X19241D01*
X18841Y-323600D01*
X19241Y-323200D01*
X18841D01*
X18441Y-322800D01*
X18041Y-323200D01*
X17641D01*
X18041Y-323600D01*
X17641Y-324000D01*
X18041D01*
X18441Y-324400D01*
Y-324000D02*
X18641Y-323800D01*
X18841D01*
X18641Y-323600D01*
X18841Y-323400D01*
X18641D01*
X18441Y-323200D01*
X18241Y-323400D01*
X18041D01*
X18241Y-323600D01*
X18041Y-323800D01*
X18241D01*
X18441Y-324000D01*
X16441Y-328400D02*
X16841Y-328000D01*
X17241D01*
X16841Y-327600D01*
X17241Y-327200D01*
X16841D01*
X16441Y-326800D01*
X16041Y-327200D01*
X15641D01*
X16041Y-327600D01*
X15641Y-328000D01*
X16041D01*
X16441Y-328400D01*
Y-328000D02*
X16641Y-327800D01*
X16841D01*
X16641Y-327600D01*
X16841Y-327400D01*
X16641D01*
X16441Y-327200D01*
X16241Y-327400D01*
X16041D01*
X16241Y-327600D01*
X16041Y-327800D01*
X16241D01*
X16441Y-328000D01*
X18441Y-340400D02*
X18841Y-340000D01*
X19241D01*
X18841Y-339600D01*
X19241Y-339200D01*
X18841D01*
X18441Y-338800D01*
X18041Y-339200D01*
X17641D01*
X18041Y-339600D01*
X17641Y-340000D01*
X18041D01*
X18441Y-340400D01*
Y-340000D02*
X18641Y-339800D01*
X18841D01*
X18641Y-339600D01*
X18841Y-339400D01*
X18641D01*
X18441Y-339200D01*
X18241Y-339400D01*
X18041D01*
X18241Y-339600D01*
X18041Y-339800D01*
X18241D01*
X18441Y-340000D01*
X16441Y-344400D02*
X16841Y-344000D01*
X17241D01*
X16841Y-343600D01*
X17241Y-343200D01*
X16841D01*
X16441Y-342800D01*
X16041Y-343200D01*
X15641D01*
X16041Y-343600D01*
X15641Y-344000D01*
X16041D01*
X16441Y-344400D01*
Y-344000D02*
X16641Y-343800D01*
X16841D01*
X16641Y-343600D01*
X16841Y-343400D01*
X16641D01*
X16441Y-343200D01*
X16241Y-343400D01*
X16041D01*
X16241Y-343600D01*
X16041Y-343800D01*
X16241D01*
X16441Y-344000D01*
Y-352400D02*
X16841Y-352000D01*
X17241D01*
X16841Y-351600D01*
X17241Y-351200D01*
X16841D01*
X16441Y-350800D01*
X16041Y-351200D01*
X15641D01*
X16041Y-351600D01*
X15641Y-352000D01*
X16041D01*
X16441Y-352400D01*
Y-352000D02*
X16641Y-351800D01*
X16841D01*
X16641Y-351600D01*
X16841Y-351400D01*
X16641D01*
X16441Y-351200D01*
X16241Y-351400D01*
X16041D01*
X16241Y-351600D01*
X16041Y-351800D01*
X16241D01*
X16441Y-352000D01*
X14441Y-140400D02*
X14841Y-140000D01*
X15241D01*
X14841Y-139600D01*
X15241Y-139200D01*
X14841D01*
X14441Y-138800D01*
X14041Y-139200D01*
X13641D01*
X14041Y-139600D01*
X13641Y-140000D01*
X14041D01*
X14441Y-140400D01*
Y-140000D02*
X14641Y-139800D01*
X14841D01*
X14641Y-139600D01*
X14841Y-139400D01*
X14641D01*
X14441Y-139200D01*
X14241Y-139400D01*
X14041D01*
X14241Y-139600D01*
X14041Y-139800D01*
X14241D01*
X14441Y-140000D01*
X12441Y-144400D02*
X12841Y-144000D01*
X13241D01*
X12841Y-143600D01*
X13241Y-143200D01*
X12841D01*
X12441Y-142800D01*
X12041Y-143200D01*
X11641D01*
X12041Y-143600D01*
X11641Y-144000D01*
X12041D01*
X12441Y-144400D01*
Y-144000D02*
X12641Y-143800D01*
X12841D01*
X12641Y-143600D01*
X12841Y-143400D01*
X12641D01*
X12441Y-143200D01*
X12241Y-143400D01*
X12041D01*
X12241Y-143600D01*
X12041Y-143800D01*
X12241D01*
X12441Y-144000D01*
X14441Y-148400D02*
X14841Y-148000D01*
X15241D01*
X14841Y-147600D01*
X15241Y-147200D01*
X14841D01*
X14441Y-146800D01*
X14041Y-147200D01*
X13641D01*
X14041Y-147600D01*
X13641Y-148000D01*
X14041D01*
X14441Y-148400D01*
Y-148000D02*
X14641Y-147800D01*
X14841D01*
X14641Y-147600D01*
X14841Y-147400D01*
X14641D01*
X14441Y-147200D01*
X14241Y-147400D01*
X14041D01*
X14241Y-147600D01*
X14041Y-147800D01*
X14241D01*
X14441Y-148000D01*
X12441Y-152400D02*
X12841Y-152000D01*
X13241D01*
X12841Y-151600D01*
X13241Y-151200D01*
X12841D01*
X12441Y-150800D01*
X12041Y-151200D01*
X11641D01*
X12041Y-151600D01*
X11641Y-152000D01*
X12041D01*
X12441Y-152400D01*
Y-152000D02*
X12641Y-151800D01*
X12841D01*
X12641Y-151600D01*
X12841Y-151400D01*
X12641D01*
X12441Y-151200D01*
X12241Y-151400D01*
X12041D01*
X12241Y-151600D01*
X12041Y-151800D01*
X12241D01*
X12441Y-152000D01*
X14441Y-164400D02*
X14841Y-164000D01*
X15241D01*
X14841Y-163600D01*
X15241Y-163200D01*
X14841D01*
X14441Y-162800D01*
X14041Y-163200D01*
X13641D01*
X14041Y-163600D01*
X13641Y-164000D01*
X14041D01*
X14441Y-164400D01*
Y-164000D02*
X14641Y-163800D01*
X14841D01*
X14641Y-163600D01*
X14841Y-163400D01*
X14641D01*
X14441Y-163200D01*
X14241Y-163400D01*
X14041D01*
X14241Y-163600D01*
X14041Y-163800D01*
X14241D01*
X14441Y-164000D01*
X12441Y-168400D02*
X12841Y-168000D01*
X13241D01*
X12841Y-167600D01*
X13241Y-167200D01*
X12841D01*
X12441Y-166800D01*
X12041Y-167200D01*
X11641D01*
X12041Y-167600D01*
X11641Y-168000D01*
X12041D01*
X12441Y-168400D01*
Y-168000D02*
X12641Y-167800D01*
X12841D01*
X12641Y-167600D01*
X12841Y-167400D01*
X12641D01*
X12441Y-167200D01*
X12241Y-167400D01*
X12041D01*
X12241Y-167600D01*
X12041Y-167800D01*
X12241D01*
X12441Y-168000D01*
X14441Y-172400D02*
X14841Y-172000D01*
X15241D01*
X14841Y-171600D01*
X15241Y-171200D01*
X14841D01*
X14441Y-170800D01*
X14041Y-171200D01*
X13641D01*
X14041Y-171600D01*
X13641Y-172000D01*
X14041D01*
X14441Y-172400D01*
Y-172000D02*
X14641Y-171800D01*
X14841D01*
X14641Y-171600D01*
X14841Y-171400D01*
X14641D01*
X14441Y-171200D01*
X14241Y-171400D01*
X14041D01*
X14241Y-171600D01*
X14041Y-171800D01*
X14241D01*
X14441Y-172000D01*
X12441Y-192400D02*
X12841Y-192000D01*
X13241D01*
X12841Y-191600D01*
X13241Y-191200D01*
X12841D01*
X12441Y-190800D01*
X12041Y-191200D01*
X11641D01*
X12041Y-191600D01*
X11641Y-192000D01*
X12041D01*
X12441Y-192400D01*
Y-192000D02*
X12641Y-191800D01*
X12841D01*
X12641Y-191600D01*
X12841Y-191400D01*
X12641D01*
X12441Y-191200D01*
X12241Y-191400D01*
X12041D01*
X12241Y-191600D01*
X12041Y-191800D01*
X12241D01*
X12441Y-192000D01*
X14441Y-196400D02*
X14841Y-196000D01*
X15241D01*
X14841Y-195600D01*
X15241Y-195200D01*
X14841D01*
X14441Y-194800D01*
X14041Y-195200D01*
X13641D01*
X14041Y-195600D01*
X13641Y-196000D01*
X14041D01*
X14441Y-196400D01*
Y-196000D02*
X14641Y-195800D01*
X14841D01*
X14641Y-195600D01*
X14841Y-195400D01*
X14641D01*
X14441Y-195200D01*
X14241Y-195400D01*
X14041D01*
X14241Y-195600D01*
X14041Y-195800D01*
X14241D01*
X14441Y-196000D01*
X12441Y-200400D02*
X12841Y-200000D01*
X13241D01*
X12841Y-199600D01*
X13241Y-199200D01*
X12841D01*
X12441Y-198800D01*
X12041Y-199200D01*
X11641D01*
X12041Y-199600D01*
X11641Y-200000D01*
X12041D01*
X12441Y-200400D01*
Y-200000D02*
X12641Y-199800D01*
X12841D01*
X12641Y-199600D01*
X12841Y-199400D01*
X12641D01*
X12441Y-199200D01*
X12241Y-199400D01*
X12041D01*
X12241Y-199600D01*
X12041Y-199800D01*
X12241D01*
X12441Y-200000D01*
X14441Y-204400D02*
X14841Y-204000D01*
X15241D01*
X14841Y-203600D01*
X15241Y-203200D01*
X14841D01*
X14441Y-202800D01*
X14041Y-203200D01*
X13641D01*
X14041Y-203600D01*
X13641Y-204000D01*
X14041D01*
X14441Y-204400D01*
Y-204000D02*
X14641Y-203800D01*
X14841D01*
X14641Y-203600D01*
X14841Y-203400D01*
X14641D01*
X14441Y-203200D01*
X14241Y-203400D01*
X14041D01*
X14241Y-203600D01*
X14041Y-203800D01*
X14241D01*
X14441Y-204000D01*
X12441Y-216400D02*
X12841Y-216000D01*
X13241D01*
X12841Y-215600D01*
X13241Y-215200D01*
X12841D01*
X12441Y-214800D01*
X12041Y-215200D01*
X11641D01*
X12041Y-215600D01*
X11641Y-216000D01*
X12041D01*
X12441Y-216400D01*
Y-216000D02*
X12641Y-215800D01*
X12841D01*
X12641Y-215600D01*
X12841Y-215400D01*
X12641D01*
X12441Y-215200D01*
X12241Y-215400D01*
X12041D01*
X12241Y-215600D01*
X12041Y-215800D01*
X12241D01*
X12441Y-216000D01*
X14441Y-220400D02*
X14841Y-220000D01*
X15241D01*
X14841Y-219600D01*
X15241Y-219200D01*
X14841D01*
X14441Y-218800D01*
X14041Y-219200D01*
X13641D01*
X14041Y-219600D01*
X13641Y-220000D01*
X14041D01*
X14441Y-220400D01*
Y-220000D02*
X14641Y-219800D01*
X14841D01*
X14641Y-219600D01*
X14841Y-219400D01*
X14641D01*
X14441Y-219200D01*
X14241Y-219400D01*
X14041D01*
X14241Y-219600D01*
X14041Y-219800D01*
X14241D01*
X14441Y-220000D01*
X12441Y-224400D02*
X12841Y-224000D01*
X13241D01*
X12841Y-223600D01*
X13241Y-223200D01*
X12841D01*
X12441Y-222800D01*
X12041Y-223200D01*
X11641D01*
X12041Y-223600D01*
X11641Y-224000D01*
X12041D01*
X12441Y-224400D01*
Y-224000D02*
X12641Y-223800D01*
X12841D01*
X12641Y-223600D01*
X12841Y-223400D01*
X12641D01*
X12441Y-223200D01*
X12241Y-223400D01*
X12041D01*
X12241Y-223600D01*
X12041Y-223800D01*
X12241D01*
X12441Y-224000D01*
X14441Y-244400D02*
X14841Y-244000D01*
X15241D01*
X14841Y-243600D01*
X15241Y-243200D01*
X14841D01*
X14441Y-242800D01*
X14041Y-243200D01*
X13641D01*
X14041Y-243600D01*
X13641Y-244000D01*
X14041D01*
X14441Y-244400D01*
Y-244000D02*
X14641Y-243800D01*
X14841D01*
X14641Y-243600D01*
X14841Y-243400D01*
X14641D01*
X14441Y-243200D01*
X14241Y-243400D01*
X14041D01*
X14241Y-243600D01*
X14041Y-243800D01*
X14241D01*
X14441Y-244000D01*
X12441Y-248400D02*
X12841Y-248000D01*
X13241D01*
X12841Y-247600D01*
X13241Y-247200D01*
X12841D01*
X12441Y-246800D01*
X12041Y-247200D01*
X11641D01*
X12041Y-247600D01*
X11641Y-248000D01*
X12041D01*
X12441Y-248400D01*
Y-248000D02*
X12641Y-247800D01*
X12841D01*
X12641Y-247600D01*
X12841Y-247400D01*
X12641D01*
X12441Y-247200D01*
X12241Y-247400D01*
X12041D01*
X12241Y-247600D01*
X12041Y-247800D01*
X12241D01*
X12441Y-248000D01*
X14441Y-252400D02*
X14841Y-252000D01*
X15241D01*
X14841Y-251600D01*
X15241Y-251200D01*
X14841D01*
X14441Y-250800D01*
X14041Y-251200D01*
X13641D01*
X14041Y-251600D01*
X13641Y-252000D01*
X14041D01*
X14441Y-252400D01*
Y-252000D02*
X14641Y-251800D01*
X14841D01*
X14641Y-251600D01*
X14841Y-251400D01*
X14641D01*
X14441Y-251200D01*
X14241Y-251400D01*
X14041D01*
X14241Y-251600D01*
X14041Y-251800D01*
X14241D01*
X14441Y-252000D01*
X12441Y-256400D02*
X12841Y-256000D01*
X13241D01*
X12841Y-255600D01*
X13241Y-255200D01*
X12841D01*
X12441Y-254800D01*
X12041Y-255200D01*
X11641D01*
X12041Y-255600D01*
X11641Y-256000D01*
X12041D01*
X12441Y-256400D01*
Y-256000D02*
X12641Y-255800D01*
X12841D01*
X12641Y-255600D01*
X12841Y-255400D01*
X12641D01*
X12441Y-255200D01*
X12241Y-255400D01*
X12041D01*
X12241Y-255600D01*
X12041Y-255800D01*
X12241D01*
X12441Y-256000D01*
X14441Y-260400D02*
X14841Y-260000D01*
X15241D01*
X14841Y-259600D01*
X15241Y-259200D01*
X14841D01*
X14441Y-258800D01*
X14041Y-259200D01*
X13641D01*
X14041Y-259600D01*
X13641Y-260000D01*
X14041D01*
X14441Y-260400D01*
Y-260000D02*
X14641Y-259800D01*
X14841D01*
X14641Y-259600D01*
X14841Y-259400D01*
X14641D01*
X14441Y-259200D01*
X14241Y-259400D01*
X14041D01*
X14241Y-259600D01*
X14041Y-259800D01*
X14241D01*
X14441Y-260000D01*
Y-268400D02*
X14841Y-268000D01*
X15241D01*
X14841Y-267600D01*
X15241Y-267200D01*
X14841D01*
X14441Y-266800D01*
X14041Y-267200D01*
X13641D01*
X14041Y-267600D01*
X13641Y-268000D01*
X14041D01*
X14441Y-268400D01*
Y-268000D02*
X14641Y-267800D01*
X14841D01*
X14641Y-267600D01*
X14841Y-267400D01*
X14641D01*
X14441Y-267200D01*
X14241Y-267400D01*
X14041D01*
X14241Y-267600D01*
X14041Y-267800D01*
X14241D01*
X14441Y-268000D01*
X12441Y-272400D02*
X12841Y-272000D01*
X13241D01*
X12841Y-271600D01*
X13241Y-271200D01*
X12841D01*
X12441Y-270800D01*
X12041Y-271200D01*
X11641D01*
X12041Y-271600D01*
X11641Y-272000D01*
X12041D01*
X12441Y-272400D01*
Y-272000D02*
X12641Y-271800D01*
X12841D01*
X12641Y-271600D01*
X12841Y-271400D01*
X12641D01*
X12441Y-271200D01*
X12241Y-271400D01*
X12041D01*
X12241Y-271600D01*
X12041Y-271800D01*
X12241D01*
X12441Y-272000D01*
X14441Y-276400D02*
X14841Y-276000D01*
X15241D01*
X14841Y-275600D01*
X15241Y-275200D01*
X14841D01*
X14441Y-274800D01*
X14041Y-275200D01*
X13641D01*
X14041Y-275600D01*
X13641Y-276000D01*
X14041D01*
X14441Y-276400D01*
Y-276000D02*
X14641Y-275800D01*
X14841D01*
X14641Y-275600D01*
X14841Y-275400D01*
X14641D01*
X14441Y-275200D01*
X14241Y-275400D01*
X14041D01*
X14241Y-275600D01*
X14041Y-275800D01*
X14241D01*
X14441Y-276000D01*
X12441Y-280400D02*
X12841Y-280000D01*
X13241D01*
X12841Y-279600D01*
X13241Y-279200D01*
X12841D01*
X12441Y-278800D01*
X12041Y-279200D01*
X11641D01*
X12041Y-279600D01*
X11641Y-280000D01*
X12041D01*
X12441Y-280400D01*
Y-280000D02*
X12641Y-279800D01*
X12841D01*
X12641Y-279600D01*
X12841Y-279400D01*
X12641D01*
X12441Y-279200D01*
X12241Y-279400D01*
X12041D01*
X12241Y-279600D01*
X12041Y-279800D01*
X12241D01*
X12441Y-280000D01*
X14441Y-292400D02*
X14841Y-292000D01*
X15241D01*
X14841Y-291600D01*
X15241Y-291200D01*
X14841D01*
X14441Y-290800D01*
X14041Y-291200D01*
X13641D01*
X14041Y-291600D01*
X13641Y-292000D01*
X14041D01*
X14441Y-292400D01*
Y-292000D02*
X14641Y-291800D01*
X14841D01*
X14641Y-291600D01*
X14841Y-291400D01*
X14641D01*
X14441Y-291200D01*
X14241Y-291400D01*
X14041D01*
X14241Y-291600D01*
X14041Y-291800D01*
X14241D01*
X14441Y-292000D01*
Y-300400D02*
X14841Y-300000D01*
X15241D01*
X14841Y-299600D01*
X15241Y-299200D01*
X14841D01*
X14441Y-298800D01*
X14041Y-299200D01*
X13641D01*
X14041Y-299600D01*
X13641Y-300000D01*
X14041D01*
X14441Y-300400D01*
Y-300000D02*
X14641Y-299800D01*
X14841D01*
X14641Y-299600D01*
X14841Y-299400D01*
X14641D01*
X14441Y-299200D01*
X14241Y-299400D01*
X14041D01*
X14241Y-299600D01*
X14041Y-299800D01*
X14241D01*
X14441Y-300000D01*
X12441Y-304400D02*
X12841Y-304000D01*
X13241D01*
X12841Y-303600D01*
X13241Y-303200D01*
X12841D01*
X12441Y-302800D01*
X12041Y-303200D01*
X11641D01*
X12041Y-303600D01*
X11641Y-304000D01*
X12041D01*
X12441Y-304400D01*
Y-304000D02*
X12641Y-303800D01*
X12841D01*
X12641Y-303600D01*
X12841Y-303400D01*
X12641D01*
X12441Y-303200D01*
X12241Y-303400D01*
X12041D01*
X12241Y-303600D01*
X12041Y-303800D01*
X12241D01*
X12441Y-304000D01*
X14441Y-308400D02*
X14841Y-308000D01*
X15241D01*
X14841Y-307600D01*
X15241Y-307200D01*
X14841D01*
X14441Y-306800D01*
X14041Y-307200D01*
X13641D01*
X14041Y-307600D01*
X13641Y-308000D01*
X14041D01*
X14441Y-308400D01*
Y-308000D02*
X14641Y-307800D01*
X14841D01*
X14641Y-307600D01*
X14841Y-307400D01*
X14641D01*
X14441Y-307200D01*
X14241Y-307400D01*
X14041D01*
X14241Y-307600D01*
X14041Y-307800D01*
X14241D01*
X14441Y-308000D01*
X12441Y-312400D02*
X12841Y-312000D01*
X13241D01*
X12841Y-311600D01*
X13241Y-311200D01*
X12841D01*
X12441Y-310800D01*
X12041Y-311200D01*
X11641D01*
X12041Y-311600D01*
X11641Y-312000D01*
X12041D01*
X12441Y-312400D01*
Y-312000D02*
X12641Y-311800D01*
X12841D01*
X12641Y-311600D01*
X12841Y-311400D01*
X12641D01*
X12441Y-311200D01*
X12241Y-311400D01*
X12041D01*
X12241Y-311600D01*
X12041Y-311800D01*
X12241D01*
X12441Y-312000D01*
X14441Y-324400D02*
X14841Y-324000D01*
X15241D01*
X14841Y-323600D01*
X15241Y-323200D01*
X14841D01*
X14441Y-322800D01*
X14041Y-323200D01*
X13641D01*
X14041Y-323600D01*
X13641Y-324000D01*
X14041D01*
X14441Y-324400D01*
Y-324000D02*
X14641Y-323800D01*
X14841D01*
X14641Y-323600D01*
X14841Y-323400D01*
X14641D01*
X14441Y-323200D01*
X14241Y-323400D01*
X14041D01*
X14241Y-323600D01*
X14041Y-323800D01*
X14241D01*
X14441Y-324000D01*
X12441Y-328400D02*
X12841Y-328000D01*
X13241D01*
X12841Y-327600D01*
X13241Y-327200D01*
X12841D01*
X12441Y-326800D01*
X12041Y-327200D01*
X11641D01*
X12041Y-327600D01*
X11641Y-328000D01*
X12041D01*
X12441Y-328400D01*
Y-328000D02*
X12641Y-327800D01*
X12841D01*
X12641Y-327600D01*
X12841Y-327400D01*
X12641D01*
X12441Y-327200D01*
X12241Y-327400D01*
X12041D01*
X12241Y-327600D01*
X12041Y-327800D01*
X12241D01*
X12441Y-328000D01*
X14441Y-332400D02*
X14841Y-332000D01*
X15241D01*
X14841Y-331600D01*
X15241Y-331200D01*
X14841D01*
X14441Y-330800D01*
X14041Y-331200D01*
X13641D01*
X14041Y-331600D01*
X13641Y-332000D01*
X14041D01*
X14441Y-332400D01*
Y-332000D02*
X14641Y-331800D01*
X14841D01*
X14641Y-331600D01*
X14841Y-331400D01*
X14641D01*
X14441Y-331200D01*
X14241Y-331400D01*
X14041D01*
X14241Y-331600D01*
X14041Y-331800D01*
X14241D01*
X14441Y-332000D01*
X12441Y-344400D02*
X12841Y-344000D01*
X13241D01*
X12841Y-343600D01*
X13241Y-343200D01*
X12841D01*
X12441Y-342800D01*
X12041Y-343200D01*
X11641D01*
X12041Y-343600D01*
X11641Y-344000D01*
X12041D01*
X12441Y-344400D01*
Y-344000D02*
X12641Y-343800D01*
X12841D01*
X12641Y-343600D01*
X12841Y-343400D01*
X12641D01*
X12441Y-343200D01*
X12241Y-343400D01*
X12041D01*
X12241Y-343600D01*
X12041Y-343800D01*
X12241D01*
X12441Y-344000D01*
Y-352400D02*
X12841Y-352000D01*
X13241D01*
X12841Y-351600D01*
X13241Y-351200D01*
X12841D01*
X12441Y-350800D01*
X12041Y-351200D01*
X11641D01*
X12041Y-351600D01*
X11641Y-352000D01*
X12041D01*
X12441Y-352400D01*
Y-352000D02*
X12641Y-351800D01*
X12841D01*
X12641Y-351600D01*
X12841Y-351400D01*
X12641D01*
X12441Y-351200D01*
X12241Y-351400D01*
X12041D01*
X12241Y-351600D01*
X12041Y-351800D01*
X12241D01*
X12441Y-352000D01*
X10441Y-140400D02*
X10841Y-140000D01*
X11241D01*
X10841Y-139600D01*
X11241Y-139200D01*
X10841D01*
X10441Y-138800D01*
X10041Y-139200D01*
X9641D01*
X10041Y-139600D01*
X9641Y-140000D01*
X10041D01*
X10441Y-140400D01*
Y-140000D02*
X10641Y-139800D01*
X10841D01*
X10641Y-139600D01*
X10841Y-139400D01*
X10641D01*
X10441Y-139200D01*
X10241Y-139400D01*
X10041D01*
X10241Y-139600D01*
X10041Y-139800D01*
X10241D01*
X10441Y-140000D01*
Y-164400D02*
X10841Y-164000D01*
X11241D01*
X10841Y-163600D01*
X11241Y-163200D01*
X10841D01*
X10441Y-162800D01*
X10041Y-163200D01*
X9641D01*
X10041Y-163600D01*
X9641Y-164000D01*
X10041D01*
X10441Y-164400D01*
Y-164000D02*
X10641Y-163800D01*
X10841D01*
X10641Y-163600D01*
X10841Y-163400D01*
X10641D01*
X10441Y-163200D01*
X10241Y-163400D01*
X10041D01*
X10241Y-163600D01*
X10041Y-163800D01*
X10241D01*
X10441Y-164000D01*
Y-172400D02*
X10841Y-172000D01*
X11241D01*
X10841Y-171600D01*
X11241Y-171200D01*
X10841D01*
X10441Y-170800D01*
X10041Y-171200D01*
X9641D01*
X10041Y-171600D01*
X9641Y-172000D01*
X10041D01*
X10441Y-172400D01*
Y-172000D02*
X10641Y-171800D01*
X10841D01*
X10641Y-171600D01*
X10841Y-171400D01*
X10641D01*
X10441Y-171200D01*
X10241Y-171400D01*
X10041D01*
X10241Y-171600D01*
X10041Y-171800D01*
X10241D01*
X10441Y-172000D01*
X8441Y-192400D02*
X8841Y-192000D01*
X9241D01*
X8841Y-191600D01*
X9241Y-191200D01*
X8841D01*
X8441Y-190800D01*
X8041Y-191200D01*
X7641D01*
X8041Y-191600D01*
X7641Y-192000D01*
X8041D01*
X8441Y-192400D01*
Y-192000D02*
X8641Y-191800D01*
X8841D01*
X8641Y-191600D01*
X8841Y-191400D01*
X8641D01*
X8441Y-191200D01*
X8241Y-191400D01*
X8041D01*
X8241Y-191600D01*
X8041Y-191800D01*
X8241D01*
X8441Y-192000D01*
X10441Y-196400D02*
X10841Y-196000D01*
X11241D01*
X10841Y-195600D01*
X11241Y-195200D01*
X10841D01*
X10441Y-194800D01*
X10041Y-195200D01*
X9641D01*
X10041Y-195600D01*
X9641Y-196000D01*
X10041D01*
X10441Y-196400D01*
Y-196000D02*
X10641Y-195800D01*
X10841D01*
X10641Y-195600D01*
X10841Y-195400D01*
X10641D01*
X10441Y-195200D01*
X10241Y-195400D01*
X10041D01*
X10241Y-195600D01*
X10041Y-195800D01*
X10241D01*
X10441Y-196000D01*
Y-204400D02*
X10841Y-204000D01*
X11241D01*
X10841Y-203600D01*
X11241Y-203200D01*
X10841D01*
X10441Y-202800D01*
X10041Y-203200D01*
X9641D01*
X10041Y-203600D01*
X9641Y-204000D01*
X10041D01*
X10441Y-204400D01*
Y-204000D02*
X10641Y-203800D01*
X10841D01*
X10641Y-203600D01*
X10841Y-203400D01*
X10641D01*
X10441Y-203200D01*
X10241Y-203400D01*
X10041D01*
X10241Y-203600D01*
X10041Y-203800D01*
X10241D01*
X10441Y-204000D01*
Y-228400D02*
X10841Y-228000D01*
X11241D01*
X10841Y-227600D01*
X11241Y-227200D01*
X10841D01*
X10441Y-226800D01*
X10041Y-227200D01*
X9641D01*
X10041Y-227600D01*
X9641Y-228000D01*
X10041D01*
X10441Y-228400D01*
Y-228000D02*
X10641Y-227800D01*
X10841D01*
X10641Y-227600D01*
X10841Y-227400D01*
X10641D01*
X10441Y-227200D01*
X10241Y-227400D01*
X10041D01*
X10241Y-227600D01*
X10041Y-227800D01*
X10241D01*
X10441Y-228000D01*
Y-244400D02*
X10841Y-244000D01*
X11241D01*
X10841Y-243600D01*
X11241Y-243200D01*
X10841D01*
X10441Y-242800D01*
X10041Y-243200D01*
X9641D01*
X10041Y-243600D01*
X9641Y-244000D01*
X10041D01*
X10441Y-244400D01*
Y-244000D02*
X10641Y-243800D01*
X10841D01*
X10641Y-243600D01*
X10841Y-243400D01*
X10641D01*
X10441Y-243200D01*
X10241Y-243400D01*
X10041D01*
X10241Y-243600D01*
X10041Y-243800D01*
X10241D01*
X10441Y-244000D01*
X8441Y-248400D02*
X8841Y-248000D01*
X9241D01*
X8841Y-247600D01*
X9241Y-247200D01*
X8841D01*
X8441Y-246800D01*
X8041Y-247200D01*
X7641D01*
X8041Y-247600D01*
X7641Y-248000D01*
X8041D01*
X8441Y-248400D01*
Y-248000D02*
X8641Y-247800D01*
X8841D01*
X8641Y-247600D01*
X8841Y-247400D01*
X8641D01*
X8441Y-247200D01*
X8241Y-247400D01*
X8041D01*
X8241Y-247600D01*
X8041Y-247800D01*
X8241D01*
X8441Y-248000D01*
X10441Y-252400D02*
X10841Y-252000D01*
X11241D01*
X10841Y-251600D01*
X11241Y-251200D01*
X10841D01*
X10441Y-250800D01*
X10041Y-251200D01*
X9641D01*
X10041Y-251600D01*
X9641Y-252000D01*
X10041D01*
X10441Y-252400D01*
Y-252000D02*
X10641Y-251800D01*
X10841D01*
X10641Y-251600D01*
X10841Y-251400D01*
X10641D01*
X10441Y-251200D01*
X10241Y-251400D01*
X10041D01*
X10241Y-251600D01*
X10041Y-251800D01*
X10241D01*
X10441Y-252000D01*
Y-260400D02*
X10841Y-260000D01*
X11241D01*
X10841Y-259600D01*
X11241Y-259200D01*
X10841D01*
X10441Y-258800D01*
X10041Y-259200D01*
X9641D01*
X10041Y-259600D01*
X9641Y-260000D01*
X10041D01*
X10441Y-260400D01*
Y-260000D02*
X10641Y-259800D01*
X10841D01*
X10641Y-259600D01*
X10841Y-259400D01*
X10641D01*
X10441Y-259200D01*
X10241Y-259400D01*
X10041D01*
X10241Y-259600D01*
X10041Y-259800D01*
X10241D01*
X10441Y-260000D01*
Y-268400D02*
X10841Y-268000D01*
X11241D01*
X10841Y-267600D01*
X11241Y-267200D01*
X10841D01*
X10441Y-266800D01*
X10041Y-267200D01*
X9641D01*
X10041Y-267600D01*
X9641Y-268000D01*
X10041D01*
X10441Y-268400D01*
Y-268000D02*
X10641Y-267800D01*
X10841D01*
X10641Y-267600D01*
X10841Y-267400D01*
X10641D01*
X10441Y-267200D01*
X10241Y-267400D01*
X10041D01*
X10241Y-267600D01*
X10041Y-267800D01*
X10241D01*
X10441Y-268000D01*
Y-276400D02*
X10841Y-276000D01*
X11241D01*
X10841Y-275600D01*
X11241Y-275200D01*
X10841D01*
X10441Y-274800D01*
X10041Y-275200D01*
X9641D01*
X10041Y-275600D01*
X9641Y-276000D01*
X10041D01*
X10441Y-276400D01*
Y-276000D02*
X10641Y-275800D01*
X10841D01*
X10641Y-275600D01*
X10841Y-275400D01*
X10641D01*
X10441Y-275200D01*
X10241Y-275400D01*
X10041D01*
X10241Y-275600D01*
X10041Y-275800D01*
X10241D01*
X10441Y-276000D01*
X8441Y-280400D02*
X8841Y-280000D01*
X9241D01*
X8841Y-279600D01*
X9241Y-279200D01*
X8841D01*
X8441Y-278800D01*
X8041Y-279200D01*
X7641D01*
X8041Y-279600D01*
X7641Y-280000D01*
X8041D01*
X8441Y-280400D01*
Y-280000D02*
X8641Y-279800D01*
X8841D01*
X8641Y-279600D01*
X8841Y-279400D01*
X8641D01*
X8441Y-279200D01*
X8241Y-279400D01*
X8041D01*
X8241Y-279600D01*
X8041Y-279800D01*
X8241D01*
X8441Y-280000D01*
X10441Y-300400D02*
X10841Y-300000D01*
X11241D01*
X10841Y-299600D01*
X11241Y-299200D01*
X10841D01*
X10441Y-298800D01*
X10041Y-299200D01*
X9641D01*
X10041Y-299600D01*
X9641Y-300000D01*
X10041D01*
X10441Y-300400D01*
Y-300000D02*
X10641Y-299800D01*
X10841D01*
X10641Y-299600D01*
X10841Y-299400D01*
X10641D01*
X10441Y-299200D01*
X10241Y-299400D01*
X10041D01*
X10241Y-299600D01*
X10041Y-299800D01*
X10241D01*
X10441Y-300000D01*
Y-324400D02*
X10841Y-324000D01*
X11241D01*
X10841Y-323600D01*
X11241Y-323200D01*
X10841D01*
X10441Y-322800D01*
X10041Y-323200D01*
X9641D01*
X10041Y-323600D01*
X9641Y-324000D01*
X10041D01*
X10441Y-324400D01*
Y-324000D02*
X10641Y-323800D01*
X10841D01*
X10641Y-323600D01*
X10841Y-323400D01*
X10641D01*
X10441Y-323200D01*
X10241Y-323400D01*
X10041D01*
X10241Y-323600D01*
X10041Y-323800D01*
X10241D01*
X10441Y-324000D01*
Y-332400D02*
X10841Y-332000D01*
X11241D01*
X10841Y-331600D01*
X11241Y-331200D01*
X10841D01*
X10441Y-330800D01*
X10041Y-331200D01*
X9641D01*
X10041Y-331600D01*
X9641Y-332000D01*
X10041D01*
X10441Y-332400D01*
Y-332000D02*
X10641Y-331800D01*
X10841D01*
X10641Y-331600D01*
X10841Y-331400D01*
X10641D01*
X10441Y-331200D01*
X10241Y-331400D01*
X10041D01*
X10241Y-331600D01*
X10041Y-331800D01*
X10241D01*
X10441Y-332000D01*
X8441Y-352400D02*
X8841Y-352000D01*
X9241D01*
X8841Y-351600D01*
X9241Y-351200D01*
X8841D01*
X8441Y-350800D01*
X8041Y-351200D01*
X7641D01*
X8041Y-351600D01*
X7641Y-352000D01*
X8041D01*
X8441Y-352400D01*
Y-352000D02*
X8641Y-351800D01*
X8841D01*
X8641Y-351600D01*
X8841Y-351400D01*
X8641D01*
X8441Y-351200D01*
X8241Y-351400D01*
X8041D01*
X8241Y-351600D01*
X8041Y-351800D01*
X8241D01*
X8441Y-352000D01*
X6441Y-140400D02*
X6841Y-140000D01*
X7241D01*
X6841Y-139600D01*
X7241Y-139200D01*
X6841D01*
X6441Y-138800D01*
X6041Y-139200D01*
X5641D01*
X6041Y-139600D01*
X5641Y-140000D01*
X6041D01*
X6441Y-140400D01*
Y-140000D02*
X6641Y-139800D01*
X6841D01*
X6641Y-139600D01*
X6841Y-139400D01*
X6641D01*
X6441Y-139200D01*
X6241Y-139400D01*
X6041D01*
X6241Y-139600D01*
X6041Y-139800D01*
X6241D01*
X6441Y-140000D01*
X4441Y-192400D02*
X4841Y-192000D01*
X5241D01*
X4841Y-191600D01*
X5241Y-191200D01*
X4841D01*
X4441Y-190800D01*
X4041Y-191200D01*
X3641D01*
X4041Y-191600D01*
X3641Y-192000D01*
X4041D01*
X4441Y-192400D01*
Y-192000D02*
X4641Y-191800D01*
X4841D01*
X4641Y-191600D01*
X4841Y-191400D01*
X4641D01*
X4441Y-191200D01*
X4241Y-191400D01*
X4041D01*
X4241Y-191600D01*
X4041Y-191800D01*
X4241D01*
X4441Y-192000D01*
X6441Y-244400D02*
X6841Y-244000D01*
X7241D01*
X6841Y-243600D01*
X7241Y-243200D01*
X6841D01*
X6441Y-242800D01*
X6041Y-243200D01*
X5641D01*
X6041Y-243600D01*
X5641Y-244000D01*
X6041D01*
X6441Y-244400D01*
Y-244000D02*
X6641Y-243800D01*
X6841D01*
X6641Y-243600D01*
X6841Y-243400D01*
X6641D01*
X6441Y-243200D01*
X6241Y-243400D01*
X6041D01*
X6241Y-243600D01*
X6041Y-243800D01*
X6241D01*
X6441Y-244000D01*
X4441Y-352400D02*
X4841Y-352000D01*
X5241D01*
X4841Y-351600D01*
X5241Y-351200D01*
X4841D01*
X4441Y-350800D01*
X4041Y-351200D01*
X3641D01*
X4041Y-351600D01*
X3641Y-352000D01*
X4041D01*
X4441Y-352400D01*
Y-352000D02*
X4641Y-351800D01*
X4841D01*
X4641Y-351600D01*
X4841Y-351400D01*
X4641D01*
X4441Y-351200D01*
X4241Y-351400D01*
X4041D01*
X4241Y-351600D01*
X4041Y-351800D01*
X4241D01*
X4441Y-352000D01*
X2441Y-244400D02*
X2841Y-244000D01*
X3241D01*
X2841Y-243600D01*
X3241Y-243200D01*
X2841D01*
X2441Y-242800D01*
X2041Y-243200D01*
X1641D01*
X2041Y-243600D01*
X1641Y-244000D01*
X2041D01*
X2441Y-244400D01*
Y-244000D02*
X2641Y-243800D01*
X2841D01*
X2641Y-243600D01*
X2841Y-243400D01*
X2641D01*
X2441Y-243200D01*
X2241Y-243400D01*
X2041D01*
X2241Y-243600D01*
X2041Y-243800D01*
X2241D01*
X2441Y-244000D01*
X441Y-352400D02*
X841Y-352000D01*
X1241D01*
X841Y-351600D01*
X1241Y-351200D01*
X841D01*
X441Y-350800D01*
X41Y-351200D01*
X-359D01*
X41Y-351600D01*
X-359Y-352000D01*
X41D01*
X441Y-352400D01*
Y-352000D02*
X641Y-351800D01*
X841D01*
X641Y-351600D01*
X841Y-351400D01*
X641D01*
X441Y-351200D01*
X241Y-351400D01*
X41D01*
X241Y-351600D01*
X41Y-351800D01*
X241D01*
X441Y-352000D01*
X-3559Y-192400D02*
X-3159Y-192000D01*
X-2759D01*
X-3159Y-191600D01*
X-2759Y-191200D01*
X-3159D01*
X-3559Y-190800D01*
X-3959Y-191200D01*
X-4359D01*
X-3959Y-191600D01*
X-4359Y-192000D01*
X-3959D01*
X-3559Y-192400D01*
Y-192000D02*
X-3359Y-191800D01*
X-3159D01*
X-3359Y-191600D01*
X-3159Y-191400D01*
X-3359D01*
X-3559Y-191200D01*
X-3759Y-191400D01*
X-3959D01*
X-3759Y-191600D01*
X-3959Y-191800D01*
X-3759D01*
X-3559Y-192000D01*
X-1559Y-244400D02*
X-1159Y-244000D01*
X-759D01*
X-1159Y-243600D01*
X-759Y-243200D01*
X-1159D01*
X-1559Y-242800D01*
X-1959Y-243200D01*
X-2359D01*
X-1959Y-243600D01*
X-2359Y-244000D01*
X-1959D01*
X-1559Y-244400D01*
Y-244000D02*
X-1359Y-243800D01*
X-1159D01*
X-1359Y-243600D01*
X-1159Y-243400D01*
X-1359D01*
X-1559Y-243200D01*
X-1759Y-243400D01*
X-1959D01*
X-1759Y-243600D01*
X-1959Y-243800D01*
X-1759D01*
X-1559Y-244000D01*
X-3559Y-352400D02*
X-3159Y-352000D01*
X-2759D01*
X-3159Y-351600D01*
X-2759Y-351200D01*
X-3159D01*
X-3559Y-350800D01*
X-3959Y-351200D01*
X-4359D01*
X-3959Y-351600D01*
X-4359Y-352000D01*
X-3959D01*
X-3559Y-352400D01*
Y-352000D02*
X-3359Y-351800D01*
X-3159D01*
X-3359Y-351600D01*
X-3159Y-351400D01*
X-3359D01*
X-3559Y-351200D01*
X-3759Y-351400D01*
X-3959D01*
X-3759Y-351600D01*
X-3959Y-351800D01*
X-3759D01*
X-3559Y-352000D01*
X-5559Y-140400D02*
X-5159Y-140000D01*
X-4759D01*
X-5159Y-139600D01*
X-4759Y-139200D01*
X-5159D01*
X-5559Y-138800D01*
X-5959Y-139200D01*
X-6359D01*
X-5959Y-139600D01*
X-6359Y-140000D01*
X-5959D01*
X-5559Y-140400D01*
Y-140000D02*
X-5359Y-139800D01*
X-5159D01*
X-5359Y-139600D01*
X-5159Y-139400D01*
X-5359D01*
X-5559Y-139200D01*
X-5759Y-139400D01*
X-5959D01*
X-5759Y-139600D01*
X-5959Y-139800D01*
X-5759D01*
X-5559Y-140000D01*
X-7559Y-144400D02*
X-7159Y-144000D01*
X-6759D01*
X-7159Y-143600D01*
X-6759Y-143200D01*
X-7159D01*
X-7559Y-142800D01*
X-7959Y-143200D01*
X-8359D01*
X-7959Y-143600D01*
X-8359Y-144000D01*
X-7959D01*
X-7559Y-144400D01*
Y-144000D02*
X-7359Y-143800D01*
X-7159D01*
X-7359Y-143600D01*
X-7159Y-143400D01*
X-7359D01*
X-7559Y-143200D01*
X-7759Y-143400D01*
X-7959D01*
X-7759Y-143600D01*
X-7959Y-143800D01*
X-7759D01*
X-7559Y-144000D01*
Y-168400D02*
X-7159Y-168000D01*
X-6759D01*
X-7159Y-167600D01*
X-6759Y-167200D01*
X-7159D01*
X-7559Y-166800D01*
X-7959Y-167200D01*
X-8359D01*
X-7959Y-167600D01*
X-8359Y-168000D01*
X-7959D01*
X-7559Y-168400D01*
Y-168000D02*
X-7359Y-167800D01*
X-7159D01*
X-7359Y-167600D01*
X-7159Y-167400D01*
X-7359D01*
X-7559Y-167200D01*
X-7759Y-167400D01*
X-7959D01*
X-7759Y-167600D01*
X-7959Y-167800D01*
X-7759D01*
X-7559Y-168000D01*
Y-192400D02*
X-7159Y-192000D01*
X-6759D01*
X-7159Y-191600D01*
X-6759Y-191200D01*
X-7159D01*
X-7559Y-190800D01*
X-7959Y-191200D01*
X-8359D01*
X-7959Y-191600D01*
X-8359Y-192000D01*
X-7959D01*
X-7559Y-192400D01*
Y-192000D02*
X-7359Y-191800D01*
X-7159D01*
X-7359Y-191600D01*
X-7159Y-191400D01*
X-7359D01*
X-7559Y-191200D01*
X-7759Y-191400D01*
X-7959D01*
X-7759Y-191600D01*
X-7959Y-191800D01*
X-7759D01*
X-7559Y-192000D01*
Y-200400D02*
X-7159Y-200000D01*
X-6759D01*
X-7159Y-199600D01*
X-6759Y-199200D01*
X-7159D01*
X-7559Y-198800D01*
X-7959Y-199200D01*
X-8359D01*
X-7959Y-199600D01*
X-8359Y-200000D01*
X-7959D01*
X-7559Y-200400D01*
Y-200000D02*
X-7359Y-199800D01*
X-7159D01*
X-7359Y-199600D01*
X-7159Y-199400D01*
X-7359D01*
X-7559Y-199200D01*
X-7759Y-199400D01*
X-7959D01*
X-7759Y-199600D01*
X-7959Y-199800D01*
X-7759D01*
X-7559Y-200000D01*
Y-224400D02*
X-7159Y-224000D01*
X-6759D01*
X-7159Y-223600D01*
X-6759Y-223200D01*
X-7159D01*
X-7559Y-222800D01*
X-7959Y-223200D01*
X-8359D01*
X-7959Y-223600D01*
X-8359Y-224000D01*
X-7959D01*
X-7559Y-224400D01*
Y-224000D02*
X-7359Y-223800D01*
X-7159D01*
X-7359Y-223600D01*
X-7159Y-223400D01*
X-7359D01*
X-7559Y-223200D01*
X-7759Y-223400D01*
X-7959D01*
X-7759Y-223600D01*
X-7959Y-223800D01*
X-7759D01*
X-7559Y-224000D01*
X-5559Y-228400D02*
X-5159Y-228000D01*
X-4759D01*
X-5159Y-227600D01*
X-4759Y-227200D01*
X-5159D01*
X-5559Y-226800D01*
X-5959Y-227200D01*
X-6359D01*
X-5959Y-227600D01*
X-6359Y-228000D01*
X-5959D01*
X-5559Y-228400D01*
Y-228000D02*
X-5359Y-227800D01*
X-5159D01*
X-5359Y-227600D01*
X-5159Y-227400D01*
X-5359D01*
X-5559Y-227200D01*
X-5759Y-227400D01*
X-5959D01*
X-5759Y-227600D01*
X-5959Y-227800D01*
X-5759D01*
X-5559Y-228000D01*
Y-244400D02*
X-5159Y-244000D01*
X-4759D01*
X-5159Y-243600D01*
X-4759Y-243200D01*
X-5159D01*
X-5559Y-242800D01*
X-5959Y-243200D01*
X-6359D01*
X-5959Y-243600D01*
X-6359Y-244000D01*
X-5959D01*
X-5559Y-244400D01*
Y-244000D02*
X-5359Y-243800D01*
X-5159D01*
X-5359Y-243600D01*
X-5159Y-243400D01*
X-5359D01*
X-5559Y-243200D01*
X-5759Y-243400D01*
X-5959D01*
X-5759Y-243600D01*
X-5959Y-243800D01*
X-5759D01*
X-5559Y-244000D01*
X-7559Y-248400D02*
X-7159Y-248000D01*
X-6759D01*
X-7159Y-247600D01*
X-6759Y-247200D01*
X-7159D01*
X-7559Y-246800D01*
X-7959Y-247200D01*
X-8359D01*
X-7959Y-247600D01*
X-8359Y-248000D01*
X-7959D01*
X-7559Y-248400D01*
Y-248000D02*
X-7359Y-247800D01*
X-7159D01*
X-7359Y-247600D01*
X-7159Y-247400D01*
X-7359D01*
X-7559Y-247200D01*
X-7759Y-247400D01*
X-7959D01*
X-7759Y-247600D01*
X-7959Y-247800D01*
X-7759D01*
X-7559Y-248000D01*
Y-280400D02*
X-7159Y-280000D01*
X-6759D01*
X-7159Y-279600D01*
X-6759Y-279200D01*
X-7159D01*
X-7559Y-278800D01*
X-7959Y-279200D01*
X-8359D01*
X-7959Y-279600D01*
X-8359Y-280000D01*
X-7959D01*
X-7559Y-280400D01*
Y-280000D02*
X-7359Y-279800D01*
X-7159D01*
X-7359Y-279600D01*
X-7159Y-279400D01*
X-7359D01*
X-7559Y-279200D01*
X-7759Y-279400D01*
X-7959D01*
X-7759Y-279600D01*
X-7959Y-279800D01*
X-7759D01*
X-7559Y-280000D01*
X-5559Y-300400D02*
X-5159Y-300000D01*
X-4759D01*
X-5159Y-299600D01*
X-4759Y-299200D01*
X-5159D01*
X-5559Y-298800D01*
X-5959Y-299200D01*
X-6359D01*
X-5959Y-299600D01*
X-6359Y-300000D01*
X-5959D01*
X-5559Y-300400D01*
Y-300000D02*
X-5359Y-299800D01*
X-5159D01*
X-5359Y-299600D01*
X-5159Y-299400D01*
X-5359D01*
X-5559Y-299200D01*
X-5759Y-299400D01*
X-5959D01*
X-5759Y-299600D01*
X-5959Y-299800D01*
X-5759D01*
X-5559Y-300000D01*
X-7559Y-304400D02*
X-7159Y-304000D01*
X-6759D01*
X-7159Y-303600D01*
X-6759Y-303200D01*
X-7159D01*
X-7559Y-302800D01*
X-7959Y-303200D01*
X-8359D01*
X-7959Y-303600D01*
X-8359Y-304000D01*
X-7959D01*
X-7559Y-304400D01*
Y-304000D02*
X-7359Y-303800D01*
X-7159D01*
X-7359Y-303600D01*
X-7159Y-303400D01*
X-7359D01*
X-7559Y-303200D01*
X-7759Y-303400D01*
X-7959D01*
X-7759Y-303600D01*
X-7959Y-303800D01*
X-7759D01*
X-7559Y-304000D01*
Y-328400D02*
X-7159Y-328000D01*
X-6759D01*
X-7159Y-327600D01*
X-6759Y-327200D01*
X-7159D01*
X-7559Y-326800D01*
X-7959Y-327200D01*
X-8359D01*
X-7959Y-327600D01*
X-8359Y-328000D01*
X-7959D01*
X-7559Y-328400D01*
Y-328000D02*
X-7359Y-327800D01*
X-7159D01*
X-7359Y-327600D01*
X-7159Y-327400D01*
X-7359D01*
X-7559Y-327200D01*
X-7759Y-327400D01*
X-7959D01*
X-7759Y-327600D01*
X-7959Y-327800D01*
X-7759D01*
X-7559Y-328000D01*
Y-352400D02*
X-7159Y-352000D01*
X-6759D01*
X-7159Y-351600D01*
X-6759Y-351200D01*
X-7159D01*
X-7559Y-350800D01*
X-7959Y-351200D01*
X-8359D01*
X-7959Y-351600D01*
X-8359Y-352000D01*
X-7959D01*
X-7559Y-352400D01*
Y-352000D02*
X-7359Y-351800D01*
X-7159D01*
X-7359Y-351600D01*
X-7159Y-351400D01*
X-7359D01*
X-7559Y-351200D01*
X-7759Y-351400D01*
X-7959D01*
X-7759Y-351600D01*
X-7959Y-351800D01*
X-7759D01*
X-7559Y-352000D01*
X-9559Y-140400D02*
X-9159Y-140000D01*
X-8759D01*
X-9159Y-139600D01*
X-8759Y-139200D01*
X-9159D01*
X-9559Y-138800D01*
X-9959Y-139200D01*
X-10359D01*
X-9959Y-139600D01*
X-10359Y-140000D01*
X-9959D01*
X-9559Y-140400D01*
Y-140000D02*
X-9359Y-139800D01*
X-9159D01*
X-9359Y-139600D01*
X-9159Y-139400D01*
X-9359D01*
X-9559Y-139200D01*
X-9759Y-139400D01*
X-9959D01*
X-9759Y-139600D01*
X-9959Y-139800D01*
X-9759D01*
X-9559Y-140000D01*
Y-172400D02*
X-9159Y-172000D01*
X-8759D01*
X-9159Y-171600D01*
X-8759Y-171200D01*
X-9159D01*
X-9559Y-170800D01*
X-9959Y-171200D01*
X-10359D01*
X-9959Y-171600D01*
X-10359Y-172000D01*
X-9959D01*
X-9559Y-172400D01*
Y-172000D02*
X-9359Y-171800D01*
X-9159D01*
X-9359Y-171600D01*
X-9159Y-171400D01*
X-9359D01*
X-9559Y-171200D01*
X-9759Y-171400D01*
X-9959D01*
X-9759Y-171600D01*
X-9959Y-171800D01*
X-9759D01*
X-9559Y-172000D01*
X-11559Y-192400D02*
X-11159Y-192000D01*
X-10759D01*
X-11159Y-191600D01*
X-10759Y-191200D01*
X-11159D01*
X-11559Y-190800D01*
X-11959Y-191200D01*
X-12359D01*
X-11959Y-191600D01*
X-12359Y-192000D01*
X-11959D01*
X-11559Y-192400D01*
Y-192000D02*
X-11359Y-191800D01*
X-11159D01*
X-11359Y-191600D01*
X-11159Y-191400D01*
X-11359D01*
X-11559Y-191200D01*
X-11759Y-191400D01*
X-11959D01*
X-11759Y-191600D01*
X-11959Y-191800D01*
X-11759D01*
X-11559Y-192000D01*
X-9559Y-196400D02*
X-9159Y-196000D01*
X-8759D01*
X-9159Y-195600D01*
X-8759Y-195200D01*
X-9159D01*
X-9559Y-194800D01*
X-9959Y-195200D01*
X-10359D01*
X-9959Y-195600D01*
X-10359Y-196000D01*
X-9959D01*
X-9559Y-196400D01*
Y-196000D02*
X-9359Y-195800D01*
X-9159D01*
X-9359Y-195600D01*
X-9159Y-195400D01*
X-9359D01*
X-9559Y-195200D01*
X-9759Y-195400D01*
X-9959D01*
X-9759Y-195600D01*
X-9959Y-195800D01*
X-9759D01*
X-9559Y-196000D01*
Y-228400D02*
X-9159Y-228000D01*
X-8759D01*
X-9159Y-227600D01*
X-8759Y-227200D01*
X-9159D01*
X-9559Y-226800D01*
X-9959Y-227200D01*
X-10359D01*
X-9959Y-227600D01*
X-10359Y-228000D01*
X-9959D01*
X-9559Y-228400D01*
Y-228000D02*
X-9359Y-227800D01*
X-9159D01*
X-9359Y-227600D01*
X-9159Y-227400D01*
X-9359D01*
X-9559Y-227200D01*
X-9759Y-227400D01*
X-9959D01*
X-9759Y-227600D01*
X-9959Y-227800D01*
X-9759D01*
X-9559Y-228000D01*
Y-244400D02*
X-9159Y-244000D01*
X-8759D01*
X-9159Y-243600D01*
X-8759Y-243200D01*
X-9159D01*
X-9559Y-242800D01*
X-9959Y-243200D01*
X-10359D01*
X-9959Y-243600D01*
X-10359Y-244000D01*
X-9959D01*
X-9559Y-244400D01*
Y-244000D02*
X-9359Y-243800D01*
X-9159D01*
X-9359Y-243600D01*
X-9159Y-243400D01*
X-9359D01*
X-9559Y-243200D01*
X-9759Y-243400D01*
X-9959D01*
X-9759Y-243600D01*
X-9959Y-243800D01*
X-9759D01*
X-9559Y-244000D01*
X-11559Y-248400D02*
X-11159Y-248000D01*
X-10759D01*
X-11159Y-247600D01*
X-10759Y-247200D01*
X-11159D01*
X-11559Y-246800D01*
X-11959Y-247200D01*
X-12359D01*
X-11959Y-247600D01*
X-12359Y-248000D01*
X-11959D01*
X-11559Y-248400D01*
Y-248000D02*
X-11359Y-247800D01*
X-11159D01*
X-11359Y-247600D01*
X-11159Y-247400D01*
X-11359D01*
X-11559Y-247200D01*
X-11759Y-247400D01*
X-11959D01*
X-11759Y-247600D01*
X-11959Y-247800D01*
X-11759D01*
X-11559Y-248000D01*
X-9559Y-252400D02*
X-9159Y-252000D01*
X-8759D01*
X-9159Y-251600D01*
X-8759Y-251200D01*
X-9159D01*
X-9559Y-250800D01*
X-9959Y-251200D01*
X-10359D01*
X-9959Y-251600D01*
X-10359Y-252000D01*
X-9959D01*
X-9559Y-252400D01*
Y-252000D02*
X-9359Y-251800D01*
X-9159D01*
X-9359Y-251600D01*
X-9159Y-251400D01*
X-9359D01*
X-9559Y-251200D01*
X-9759Y-251400D01*
X-9959D01*
X-9759Y-251600D01*
X-9959Y-251800D01*
X-9759D01*
X-9559Y-252000D01*
Y-276400D02*
X-9159Y-276000D01*
X-8759D01*
X-9159Y-275600D01*
X-8759Y-275200D01*
X-9159D01*
X-9559Y-274800D01*
X-9959Y-275200D01*
X-10359D01*
X-9959Y-275600D01*
X-10359Y-276000D01*
X-9959D01*
X-9559Y-276400D01*
Y-276000D02*
X-9359Y-275800D01*
X-9159D01*
X-9359Y-275600D01*
X-9159Y-275400D01*
X-9359D01*
X-9559Y-275200D01*
X-9759Y-275400D01*
X-9959D01*
X-9759Y-275600D01*
X-9959Y-275800D01*
X-9759D01*
X-9559Y-276000D01*
X-11559Y-280400D02*
X-11159Y-280000D01*
X-10759D01*
X-11159Y-279600D01*
X-10759Y-279200D01*
X-11159D01*
X-11559Y-278800D01*
X-11959Y-279200D01*
X-12359D01*
X-11959Y-279600D01*
X-12359Y-280000D01*
X-11959D01*
X-11559Y-280400D01*
Y-280000D02*
X-11359Y-279800D01*
X-11159D01*
X-11359Y-279600D01*
X-11159Y-279400D01*
X-11359D01*
X-11559Y-279200D01*
X-11759Y-279400D01*
X-11959D01*
X-11759Y-279600D01*
X-11959Y-279800D01*
X-11759D01*
X-11559Y-280000D01*
X-9559Y-300400D02*
X-9159Y-300000D01*
X-8759D01*
X-9159Y-299600D01*
X-8759Y-299200D01*
X-9159D01*
X-9559Y-298800D01*
X-9959Y-299200D01*
X-10359D01*
X-9959Y-299600D01*
X-10359Y-300000D01*
X-9959D01*
X-9559Y-300400D01*
Y-300000D02*
X-9359Y-299800D01*
X-9159D01*
X-9359Y-299600D01*
X-9159Y-299400D01*
X-9359D01*
X-9559Y-299200D01*
X-9759Y-299400D01*
X-9959D01*
X-9759Y-299600D01*
X-9959Y-299800D01*
X-9759D01*
X-9559Y-300000D01*
Y-332400D02*
X-9159Y-332000D01*
X-8759D01*
X-9159Y-331600D01*
X-8759Y-331200D01*
X-9159D01*
X-9559Y-330800D01*
X-9959Y-331200D01*
X-10359D01*
X-9959Y-331600D01*
X-10359Y-332000D01*
X-9959D01*
X-9559Y-332400D01*
Y-332000D02*
X-9359Y-331800D01*
X-9159D01*
X-9359Y-331600D01*
X-9159Y-331400D01*
X-9359D01*
X-9559Y-331200D01*
X-9759Y-331400D01*
X-9959D01*
X-9759Y-331600D01*
X-9959Y-331800D01*
X-9759D01*
X-9559Y-332000D01*
X-11559Y-352400D02*
X-11159Y-352000D01*
X-10759D01*
X-11159Y-351600D01*
X-10759Y-351200D01*
X-11159D01*
X-11559Y-350800D01*
X-11959Y-351200D01*
X-12359D01*
X-11959Y-351600D01*
X-12359Y-352000D01*
X-11959D01*
X-11559Y-352400D01*
Y-352000D02*
X-11359Y-351800D01*
X-11159D01*
X-11359Y-351600D01*
X-11159Y-351400D01*
X-11359D01*
X-11559Y-351200D01*
X-11759Y-351400D01*
X-11959D01*
X-11759Y-351600D01*
X-11959Y-351800D01*
X-11759D01*
X-11559Y-352000D01*
X-13559Y-140400D02*
X-13159Y-140000D01*
X-12759D01*
X-13159Y-139600D01*
X-12759Y-139200D01*
X-13159D01*
X-13559Y-138800D01*
X-13959Y-139200D01*
X-14359D01*
X-13959Y-139600D01*
X-14359Y-140000D01*
X-13959D01*
X-13559Y-140400D01*
Y-140000D02*
X-13359Y-139800D01*
X-13159D01*
X-13359Y-139600D01*
X-13159Y-139400D01*
X-13359D01*
X-13559Y-139200D01*
X-13759Y-139400D01*
X-13959D01*
X-13759Y-139600D01*
X-13959Y-139800D01*
X-13759D01*
X-13559Y-140000D01*
X-15559Y-192400D02*
X-15159Y-192000D01*
X-14759D01*
X-15159Y-191600D01*
X-14759Y-191200D01*
X-15159D01*
X-15559Y-190800D01*
X-15959Y-191200D01*
X-16359D01*
X-15959Y-191600D01*
X-16359Y-192000D01*
X-15959D01*
X-15559Y-192400D01*
Y-192000D02*
X-15359Y-191800D01*
X-15159D01*
X-15359Y-191600D01*
X-15159Y-191400D01*
X-15359D01*
X-15559Y-191200D01*
X-15759Y-191400D01*
X-15959D01*
X-15759Y-191600D01*
X-15959Y-191800D01*
X-15759D01*
X-15559Y-192000D01*
X-13559Y-244400D02*
X-13159Y-244000D01*
X-12759D01*
X-13159Y-243600D01*
X-12759Y-243200D01*
X-13159D01*
X-13559Y-242800D01*
X-13959Y-243200D01*
X-14359D01*
X-13959Y-243600D01*
X-14359Y-244000D01*
X-13959D01*
X-13559Y-244400D01*
Y-244000D02*
X-13359Y-243800D01*
X-13159D01*
X-13359Y-243600D01*
X-13159Y-243400D01*
X-13359D01*
X-13559Y-243200D01*
X-13759Y-243400D01*
X-13959D01*
X-13759Y-243600D01*
X-13959Y-243800D01*
X-13759D01*
X-13559Y-244000D01*
X-15559Y-352400D02*
X-15159Y-352000D01*
X-14759D01*
X-15159Y-351600D01*
X-14759Y-351200D01*
X-15159D01*
X-15559Y-350800D01*
X-15959Y-351200D01*
X-16359D01*
X-15959Y-351600D01*
X-16359Y-352000D01*
X-15959D01*
X-15559Y-352400D01*
Y-352000D02*
X-15359Y-351800D01*
X-15159D01*
X-15359Y-351600D01*
X-15159Y-351400D01*
X-15359D01*
X-15559Y-351200D01*
X-15759Y-351400D01*
X-15959D01*
X-15759Y-351600D01*
X-15959Y-351800D01*
X-15759D01*
X-15559Y-352000D01*
X-19559Y-264400D02*
X-19159Y-264000D01*
X-18759D01*
X-19159Y-263600D01*
X-18759Y-263200D01*
X-19159D01*
X-19559Y-262800D01*
X-19959Y-263200D01*
X-20359D01*
X-19959Y-263600D01*
X-20359Y-264000D01*
X-19959D01*
X-19559Y-264400D01*
Y-264000D02*
X-19359Y-263800D01*
X-19159D01*
X-19359Y-263600D01*
X-19159Y-263400D01*
X-19359D01*
X-19559Y-263200D01*
X-19759Y-263400D01*
X-19959D01*
X-19759Y-263600D01*
X-19959Y-263800D01*
X-19759D01*
X-19559Y-264000D01*
Y-352400D02*
X-19159Y-352000D01*
X-18759D01*
X-19159Y-351600D01*
X-18759Y-351200D01*
X-19159D01*
X-19559Y-350800D01*
X-19959Y-351200D01*
X-20359D01*
X-19959Y-351600D01*
X-20359Y-352000D01*
X-19959D01*
X-19559Y-352400D01*
Y-352000D02*
X-19359Y-351800D01*
X-19159D01*
X-19359Y-351600D01*
X-19159Y-351400D01*
X-19359D01*
X-19559Y-351200D01*
X-19759Y-351400D01*
X-19959D01*
X-19759Y-351600D01*
X-19959Y-351800D01*
X-19759D01*
X-19559Y-352000D01*
X-23559Y-160400D02*
X-23159Y-160000D01*
X-22759D01*
X-23159Y-159600D01*
X-22759Y-159200D01*
X-23159D01*
X-23559Y-158800D01*
X-23959Y-159200D01*
X-24359D01*
X-23959Y-159600D01*
X-24359Y-160000D01*
X-23959D01*
X-23559Y-160400D01*
Y-160000D02*
X-23359Y-159800D01*
X-23159D01*
X-23359Y-159600D01*
X-23159Y-159400D01*
X-23359D01*
X-23559Y-159200D01*
X-23759Y-159400D01*
X-23959D01*
X-23759Y-159600D01*
X-23959Y-159800D01*
X-23759D01*
X-23559Y-160000D01*
Y-192400D02*
X-23159Y-192000D01*
X-22759D01*
X-23159Y-191600D01*
X-22759Y-191200D01*
X-23159D01*
X-23559Y-190800D01*
X-23959Y-191200D01*
X-24359D01*
X-23959Y-191600D01*
X-24359Y-192000D01*
X-23959D01*
X-23559Y-192400D01*
Y-192000D02*
X-23359Y-191800D01*
X-23159D01*
X-23359Y-191600D01*
X-23159Y-191400D01*
X-23359D01*
X-23559Y-191200D01*
X-23759Y-191400D01*
X-23959D01*
X-23759Y-191600D01*
X-23959Y-191800D01*
X-23759D01*
X-23559Y-192000D01*
X-21559Y-212400D02*
X-21159Y-212000D01*
X-20759D01*
X-21159Y-211600D01*
X-20759Y-211200D01*
X-21159D01*
X-21559Y-210800D01*
X-21959Y-211200D01*
X-22359D01*
X-21959Y-211600D01*
X-22359Y-212000D01*
X-21959D01*
X-21559Y-212400D01*
Y-212000D02*
X-21359Y-211800D01*
X-21159D01*
X-21359Y-211600D01*
X-21159Y-211400D01*
X-21359D01*
X-21559Y-211200D01*
X-21759Y-211400D01*
X-21959D01*
X-21759Y-211600D01*
X-21959Y-211800D01*
X-21759D01*
X-21559Y-212000D01*
X-23559Y-264400D02*
X-23159Y-264000D01*
X-22759D01*
X-23159Y-263600D01*
X-22759Y-263200D01*
X-23159D01*
X-23559Y-262800D01*
X-23959Y-263200D01*
X-24359D01*
X-23959Y-263600D01*
X-24359Y-264000D01*
X-23959D01*
X-23559Y-264400D01*
Y-264000D02*
X-23359Y-263800D01*
X-23159D01*
X-23359Y-263600D01*
X-23159Y-263400D01*
X-23359D01*
X-23559Y-263200D01*
X-23759Y-263400D01*
X-23959D01*
X-23759Y-263600D01*
X-23959Y-263800D01*
X-23759D01*
X-23559Y-264000D01*
X-21559Y-316400D02*
X-21159Y-316000D01*
X-20759D01*
X-21159Y-315600D01*
X-20759Y-315200D01*
X-21159D01*
X-21559Y-314800D01*
X-21959Y-315200D01*
X-22359D01*
X-21959Y-315600D01*
X-22359Y-316000D01*
X-21959D01*
X-21559Y-316400D01*
Y-316000D02*
X-21359Y-315800D01*
X-21159D01*
X-21359Y-315600D01*
X-21159Y-315400D01*
X-21359D01*
X-21559Y-315200D01*
X-21759Y-315400D01*
X-21959D01*
X-21759Y-315600D01*
X-21959Y-315800D01*
X-21759D01*
X-21559Y-316000D01*
X-23559Y-352400D02*
X-23159Y-352000D01*
X-22759D01*
X-23159Y-351600D01*
X-22759Y-351200D01*
X-23159D01*
X-23559Y-350800D01*
X-23959Y-351200D01*
X-24359D01*
X-23959Y-351600D01*
X-24359Y-352000D01*
X-23959D01*
X-23559Y-352400D01*
Y-352000D02*
X-23359Y-351800D01*
X-23159D01*
X-23359Y-351600D01*
X-23159Y-351400D01*
X-23359D01*
X-23559Y-351200D01*
X-23759Y-351400D01*
X-23959D01*
X-23759Y-351600D01*
X-23959Y-351800D01*
X-23759D01*
X-23559Y-352000D01*
X-25559Y-140400D02*
X-25159Y-140000D01*
X-24759D01*
X-25159Y-139600D01*
X-24759Y-139200D01*
X-25159D01*
X-25559Y-138800D01*
X-25959Y-139200D01*
X-26359D01*
X-25959Y-139600D01*
X-26359Y-140000D01*
X-25959D01*
X-25559Y-140400D01*
Y-140000D02*
X-25359Y-139800D01*
X-25159D01*
X-25359Y-139600D01*
X-25159Y-139400D01*
X-25359D01*
X-25559Y-139200D01*
X-25759Y-139400D01*
X-25959D01*
X-25759Y-139600D01*
X-25959Y-139800D01*
X-25759D01*
X-25559Y-140000D01*
Y-156400D02*
X-25159Y-156000D01*
X-24759D01*
X-25159Y-155600D01*
X-24759Y-155200D01*
X-25159D01*
X-25559Y-154800D01*
X-25959Y-155200D01*
X-26359D01*
X-25959Y-155600D01*
X-26359Y-156000D01*
X-25959D01*
X-25559Y-156400D01*
Y-156000D02*
X-25359Y-155800D01*
X-25159D01*
X-25359Y-155600D01*
X-25159Y-155400D01*
X-25359D01*
X-25559Y-155200D01*
X-25759Y-155400D01*
X-25959D01*
X-25759Y-155600D01*
X-25959Y-155800D01*
X-25759D01*
X-25559Y-156000D01*
Y-212400D02*
X-25159Y-212000D01*
X-24759D01*
X-25159Y-211600D01*
X-24759Y-211200D01*
X-25159D01*
X-25559Y-210800D01*
X-25959Y-211200D01*
X-26359D01*
X-25959Y-211600D01*
X-26359Y-212000D01*
X-25959D01*
X-25559Y-212400D01*
Y-212000D02*
X-25359Y-211800D01*
X-25159D01*
X-25359Y-211600D01*
X-25159Y-211400D01*
X-25359D01*
X-25559Y-211200D01*
X-25759Y-211400D01*
X-25959D01*
X-25759Y-211600D01*
X-25959Y-211800D01*
X-25759D01*
X-25559Y-212000D01*
Y-260400D02*
X-25159Y-260000D01*
X-24759D01*
X-25159Y-259600D01*
X-24759Y-259200D01*
X-25159D01*
X-25559Y-258800D01*
X-25959Y-259200D01*
X-26359D01*
X-25959Y-259600D01*
X-26359Y-260000D01*
X-25959D01*
X-25559Y-260400D01*
Y-260000D02*
X-25359Y-259800D01*
X-25159D01*
X-25359Y-259600D01*
X-25159Y-259400D01*
X-25359D01*
X-25559Y-259200D01*
X-25759Y-259400D01*
X-25959D01*
X-25759Y-259600D01*
X-25959Y-259800D01*
X-25759D01*
X-25559Y-260000D01*
Y-268400D02*
X-25159Y-268000D01*
X-24759D01*
X-25159Y-267600D01*
X-24759Y-267200D01*
X-25159D01*
X-25559Y-266800D01*
X-25959Y-267200D01*
X-26359D01*
X-25959Y-267600D01*
X-26359Y-268000D01*
X-25959D01*
X-25559Y-268400D01*
Y-268000D02*
X-25359Y-267800D01*
X-25159D01*
X-25359Y-267600D01*
X-25159Y-267400D01*
X-25359D01*
X-25559Y-267200D01*
X-25759Y-267400D01*
X-25959D01*
X-25759Y-267600D01*
X-25959Y-267800D01*
X-25759D01*
X-25559Y-268000D01*
Y-300400D02*
X-25159Y-300000D01*
X-24759D01*
X-25159Y-299600D01*
X-24759Y-299200D01*
X-25159D01*
X-25559Y-298800D01*
X-25959Y-299200D01*
X-26359D01*
X-25959Y-299600D01*
X-26359Y-300000D01*
X-25959D01*
X-25559Y-300400D01*
Y-300000D02*
X-25359Y-299800D01*
X-25159D01*
X-25359Y-299600D01*
X-25159Y-299400D01*
X-25359D01*
X-25559Y-299200D01*
X-25759Y-299400D01*
X-25959D01*
X-25759Y-299600D01*
X-25959Y-299800D01*
X-25759D01*
X-25559Y-300000D01*
Y-316400D02*
X-25159Y-316000D01*
X-24759D01*
X-25159Y-315600D01*
X-24759Y-315200D01*
X-25159D01*
X-25559Y-314800D01*
X-25959Y-315200D01*
X-26359D01*
X-25959Y-315600D01*
X-26359Y-316000D01*
X-25959D01*
X-25559Y-316400D01*
Y-316000D02*
X-25359Y-315800D01*
X-25159D01*
X-25359Y-315600D01*
X-25159Y-315400D01*
X-25359D01*
X-25559Y-315200D01*
X-25759Y-315400D01*
X-25959D01*
X-25759Y-315600D01*
X-25959Y-315800D01*
X-25759D01*
X-25559Y-316000D01*
X269685Y-137643D02*
X270085Y-137242D01*
X270485D01*
X270085Y-136843D01*
X270485Y-136442D01*
X270085D01*
X269685Y-136042D01*
X269285Y-136442D01*
X268885D01*
X269285Y-136843D01*
X268885Y-137242D01*
X269285D01*
X269685Y-137643D01*
Y-137242D02*
X269885Y-137042D01*
X270085D01*
X269885Y-136843D01*
X270085Y-136643D01*
X269885D01*
X269685Y-136442D01*
X269485Y-136643D01*
X269285D01*
X269485Y-136843D01*
X269285Y-137042D01*
X269485D01*
X269685Y-137242D01*
X234252Y-134542D02*
X234652Y-134142D01*
X235052D01*
X234652Y-133742D01*
X235052Y-133342D01*
X234652D01*
X234252Y-132942D01*
X233852Y-133342D01*
X233452D01*
X233852Y-133742D01*
X233452Y-134142D01*
X233852D01*
X234252Y-134542D01*
Y-134142D02*
X234452Y-133942D01*
X234652D01*
X234452Y-133742D01*
X234652Y-133542D01*
X234452D01*
X234252Y-133342D01*
X234052Y-133542D01*
X233852D01*
X234052Y-133742D01*
X233852Y-133942D01*
X234052D01*
X234252Y-134142D01*
X263779Y-106951D02*
X264179Y-106551D01*
X264580D01*
X264179Y-106151D01*
X264580Y-105751D01*
X264179D01*
X263779Y-105351D01*
X263380Y-105751D01*
X262980D01*
X263380Y-106151D01*
X262980Y-106551D01*
X263380D01*
X263779Y-106951D01*
Y-106551D02*
X263980Y-106351D01*
X264179D01*
X263980Y-106151D01*
X264179Y-105951D01*
X263980D01*
X263779Y-105751D01*
X263580Y-105951D01*
X263380D01*
X263580Y-106151D01*
X263380Y-106351D01*
X263580D01*
X263779Y-106551D01*
X71850Y-148438D02*
X72250Y-148038D01*
X72650D01*
X72250Y-147638D01*
X72650Y-147238D01*
X72250D01*
X71850Y-146838D01*
X71450Y-147238D01*
X71050D01*
X71450Y-147638D01*
X71050Y-148038D01*
X71450D01*
X71850Y-148438D01*
Y-148038D02*
X72050Y-147838D01*
X72250D01*
X72050Y-147638D01*
X72250Y-147438D01*
X72050D01*
X71850Y-147238D01*
X71650Y-147438D01*
X71450D01*
X71650Y-147638D01*
X71450Y-147838D01*
X71650D01*
X71850Y-148038D01*
X75787Y-132690D02*
X76187Y-132290D01*
X76587D01*
X76187Y-131890D01*
X76587Y-131490D01*
X76187D01*
X75787Y-131090D01*
X75387Y-131490D01*
X74987D01*
X75387Y-131890D01*
X74987Y-132290D01*
X75387D01*
X75787Y-132690D01*
Y-132290D02*
X75987Y-132090D01*
X76187D01*
X75987Y-131890D01*
X76187Y-131690D01*
X75987D01*
X75787Y-131490D01*
X75587Y-131690D01*
X75387D01*
X75587Y-131890D01*
X75387Y-132090D01*
X75587D01*
X75787Y-132290D01*
X643701Y-64776D02*
X644101Y-64376D01*
X644501D01*
X644101Y-63976D01*
X644501Y-63576D01*
X644101D01*
X643701Y-63176D01*
X643301Y-63576D01*
X642901D01*
X643301Y-63976D01*
X642901Y-64376D01*
X643301D01*
X643701Y-64776D01*
Y-64376D02*
X643901Y-64176D01*
X644101D01*
X643901Y-63976D01*
X644101Y-63776D01*
X643901D01*
X643701Y-63576D01*
X643501Y-63776D01*
X643301D01*
X643501Y-63976D01*
X643301Y-64176D01*
X643501D01*
X643701Y-64376D01*
X644685Y-46076D02*
X645085Y-45676D01*
X645485D01*
X645085Y-45276D01*
X645485Y-44876D01*
X645085D01*
X644685Y-44476D01*
X644285Y-44876D01*
X643885D01*
X644285Y-45276D01*
X643885Y-45676D01*
X644285D01*
X644685Y-46076D01*
Y-45676D02*
X644885Y-45476D01*
X645085D01*
X644885Y-45276D01*
X645085Y-45076D01*
X644885D01*
X644685Y-44876D01*
X644485Y-45076D01*
X644285D01*
X644485Y-45276D01*
X644285Y-45476D01*
X644485D01*
X644685Y-45676D01*
X623000Y-38202D02*
X623400Y-37802D01*
X623800D01*
X623400Y-37402D01*
X623800Y-37002D01*
X623400D01*
X623000Y-36602D01*
X622600Y-37002D01*
X622200D01*
X622600Y-37402D01*
X622200Y-37802D01*
X622600D01*
X623000Y-38202D01*
Y-37802D02*
X623200Y-37602D01*
X623400D01*
X623200Y-37402D01*
X623400Y-37202D01*
X623200D01*
X623000Y-37002D01*
X622800Y-37202D01*
X622600D01*
X622800Y-37402D01*
X622600Y-37602D01*
X622800D01*
X623000Y-37802D01*
X610236Y-9658D02*
X610636Y-9258D01*
X611036D01*
X610636Y-8858D01*
X611036Y-8458D01*
X610636D01*
X610236Y-8058D01*
X609836Y-8458D01*
X609436D01*
X609836Y-8858D01*
X609436Y-9258D01*
X609836D01*
X610236Y-9658D01*
Y-9258D02*
X610436Y-9058D01*
X610636D01*
X610436Y-8858D01*
X610636Y-8658D01*
X610436D01*
X610236Y-8458D01*
X610036Y-8658D01*
X609836D01*
X610036Y-8858D01*
X609836Y-9058D01*
X610036D01*
X610236Y-9258D01*
X609252Y-27375D02*
X609652Y-26975D01*
X610052D01*
X609652Y-26575D01*
X610052Y-26175D01*
X609652D01*
X609252Y-25775D01*
X608852Y-26175D01*
X608452D01*
X608852Y-26575D01*
X608452Y-26975D01*
X608852D01*
X609252Y-27375D01*
Y-26975D02*
X609452Y-26775D01*
X609652D01*
X609452Y-26575D01*
X609652Y-26375D01*
X609452D01*
X609252Y-26175D01*
X609052Y-26375D01*
X608852D01*
X609052Y-26575D01*
X608852Y-26775D01*
X609052D01*
X609252Y-26975D01*
X98425Y-103162D02*
X98825Y-102762D01*
X99225D01*
X98825Y-102362D01*
X99225Y-101962D01*
X98825D01*
X98425Y-101562D01*
X98025Y-101962D01*
X97625D01*
X98025Y-102362D01*
X97625Y-102762D01*
X98025D01*
X98425Y-103162D01*
Y-102762D02*
X98625Y-102562D01*
X98825D01*
X98625Y-102362D01*
X98825Y-102162D01*
X98625D01*
X98425Y-101962D01*
X98225Y-102162D01*
X98025D01*
X98225Y-102362D01*
X98025Y-102562D01*
X98225D01*
X98425Y-102762D01*
X89567Y-103162D02*
X89967Y-102762D01*
X90367D01*
X89967Y-102362D01*
X90367Y-101962D01*
X89967D01*
X89567Y-101562D01*
X89167Y-101962D01*
X88767D01*
X89167Y-102362D01*
X88767Y-102762D01*
X89167D01*
X89567Y-103162D01*
Y-102762D02*
X89767Y-102562D01*
X89967D01*
X89767Y-102362D01*
X89967Y-102162D01*
X89767D01*
X89567Y-101962D01*
X89367Y-102162D01*
X89167D01*
X89367Y-102362D01*
X89167Y-102562D01*
X89367D01*
X89567Y-102762D01*
X85630Y-314776D02*
X86030Y-314376D01*
X86430D01*
X86030Y-313976D01*
X86430Y-313576D01*
X86030D01*
X85630Y-313176D01*
X85230Y-313576D01*
X84830D01*
X85230Y-313976D01*
X84830Y-314376D01*
X85230D01*
X85630Y-314776D01*
Y-314376D02*
X85830Y-314176D01*
X86030D01*
X85830Y-313976D01*
X86030Y-313776D01*
X85830D01*
X85630Y-313576D01*
X85430Y-313776D01*
X85230D01*
X85430Y-313976D01*
X85230Y-314176D01*
X85430D01*
X85630Y-314376D01*
X86614Y-259658D02*
X87014Y-259258D01*
X87414D01*
X87014Y-258858D01*
X87414Y-258458D01*
X87014D01*
X86614Y-258058D01*
X86214Y-258458D01*
X85814D01*
X86214Y-258858D01*
X85814Y-259258D01*
X86214D01*
X86614Y-259658D01*
Y-259258D02*
X86814Y-259058D01*
X87014D01*
X86814Y-258858D01*
X87014Y-258658D01*
X86814D01*
X86614Y-258458D01*
X86414Y-258658D01*
X86214D01*
X86414Y-258858D01*
X86214Y-259058D01*
X86414D01*
X86614Y-259258D01*
X81693Y-206509D02*
X82093Y-206109D01*
X82493D01*
X82093Y-205709D01*
X82493Y-205309D01*
X82093D01*
X81693Y-204909D01*
X81293Y-205309D01*
X80893D01*
X81293Y-205709D01*
X80893Y-206109D01*
X81293D01*
X81693Y-206509D01*
Y-206109D02*
X81893Y-205909D01*
X82093D01*
X81893Y-205709D01*
X82093Y-205509D01*
X81893D01*
X81693Y-205309D01*
X81493Y-205509D01*
X81293D01*
X81493Y-205709D01*
X81293Y-205909D01*
X81493D01*
X81693Y-206109D01*
X86614Y-111036D02*
X87014Y-110636D01*
X87414D01*
X87014Y-110236D01*
X87414Y-109836D01*
X87014D01*
X86614Y-109436D01*
X86214Y-109836D01*
X85814D01*
X86214Y-110236D01*
X85814Y-110636D01*
X86214D01*
X86614Y-111036D01*
Y-110636D02*
X86814Y-110436D01*
X87014D01*
X86814Y-110236D01*
X87014Y-110036D01*
X86814D01*
X86614Y-109836D01*
X86414Y-110036D01*
X86214D01*
X86414Y-110236D01*
X86214Y-110436D01*
X86414D01*
X86614Y-110636D01*
X360236Y-269386D02*
X360636Y-268986D01*
X361036D01*
X360636Y-268586D01*
X361036Y-268186D01*
X360636D01*
X360236Y-267786D01*
X359836Y-268186D01*
X359436D01*
X359836Y-268586D01*
X359436Y-268986D01*
X359836D01*
X360236Y-269386D01*
Y-268986D02*
X360436Y-268786D01*
X360636D01*
X360436Y-268586D01*
X360636Y-268386D01*
X360436D01*
X360236Y-268186D01*
X360036Y-268386D01*
X359836D01*
X360036Y-268586D01*
X359836Y-268786D01*
X360036D01*
X360236Y-268986D01*
Y-273290D02*
X360636Y-272890D01*
X361036D01*
X360636Y-272490D01*
X361036Y-272090D01*
X360636D01*
X360236Y-271690D01*
X359836Y-272090D01*
X359436D01*
X359836Y-272490D01*
X359436Y-272890D01*
X359836D01*
X360236Y-273290D01*
Y-272890D02*
X360436Y-272690D01*
X360636D01*
X360436Y-272490D01*
X360636Y-272290D01*
X360436D01*
X360236Y-272090D01*
X360036Y-272290D01*
X359836D01*
X360036Y-272490D01*
X359836Y-272690D01*
X360036D01*
X360236Y-272890D01*
X63976Y-228162D02*
X64376Y-227762D01*
X64776D01*
X64376Y-227362D01*
X64776Y-226962D01*
X64376D01*
X63976Y-226562D01*
X63576Y-226962D01*
X63176D01*
X63576Y-227362D01*
X63176Y-227762D01*
X63576D01*
X63976Y-228162D01*
Y-227762D02*
X64176Y-227562D01*
X64376D01*
X64176Y-227362D01*
X64376Y-227162D01*
X64176D01*
X63976Y-226962D01*
X63776Y-227162D01*
X63576D01*
X63776Y-227362D01*
X63576Y-227562D01*
X63776D01*
X63976Y-227762D01*
X68898Y-286233D02*
X69298Y-285833D01*
X69698D01*
X69298Y-285433D01*
X69698Y-285033D01*
X69298D01*
X68898Y-284633D01*
X68498Y-285033D01*
X68098D01*
X68498Y-285433D01*
X68098Y-285833D01*
X68498D01*
X68898Y-286233D01*
Y-285833D02*
X69098Y-285633D01*
X69298D01*
X69098Y-285433D01*
X69298Y-285233D01*
X69098D01*
X68898Y-285033D01*
X68698Y-285233D01*
X68498D01*
X68698Y-285433D01*
X68498Y-285633D01*
X68698D01*
X68898Y-285833D01*
X67913Y-341351D02*
X68313Y-340951D01*
X68713D01*
X68313Y-340551D01*
X68713Y-340151D01*
X68313D01*
X67913Y-339751D01*
X67513Y-340151D01*
X67113D01*
X67513Y-340551D01*
X67113Y-340951D01*
X67513D01*
X67913Y-341351D01*
Y-340951D02*
X68113Y-340751D01*
X68313D01*
X68113Y-340551D01*
X68313Y-340351D01*
X68113D01*
X67913Y-340151D01*
X67713Y-340351D01*
X67513D01*
X67713Y-340551D01*
X67513Y-340751D01*
X67713D01*
X67913Y-340951D01*
X68573Y-180121D02*
X68973Y-179721D01*
X69373D01*
X68973Y-179321D01*
X69373Y-178921D01*
X68973D01*
X68573Y-178521D01*
X68173Y-178921D01*
X67773D01*
X68173Y-179321D01*
X67773Y-179721D01*
X68173D01*
X68573Y-180121D01*
Y-179721D02*
X68773Y-179521D01*
X68973D01*
X68773Y-179321D01*
X68973Y-179121D01*
X68773D01*
X68573Y-178921D01*
X68373Y-179121D01*
X68173D01*
X68373Y-179321D01*
X68173Y-179521D01*
X68373D01*
X68573Y-179721D01*
X44291Y-253753D02*
X44691Y-253353D01*
X45091D01*
X44691Y-252953D01*
X45091Y-252553D01*
X44691D01*
X44291Y-252153D01*
X43891Y-252553D01*
X43491D01*
X43891Y-252953D01*
X43491Y-253353D01*
X43891D01*
X44291Y-253753D01*
Y-253353D02*
X44491Y-253153D01*
X44691D01*
X44491Y-252953D01*
X44691Y-252753D01*
X44491D01*
X44291Y-252553D01*
X44091Y-252753D01*
X43891D01*
X44091Y-252953D01*
X43891Y-253153D01*
X44091D01*
X44291Y-253353D01*
Y-273438D02*
X44691Y-273038D01*
X45091D01*
X44691Y-272638D01*
X45091Y-272238D01*
X44691D01*
X44291Y-271838D01*
X43891Y-272238D01*
X43491D01*
X43891Y-272638D01*
X43491Y-273038D01*
X43891D01*
X44291Y-273438D01*
Y-273038D02*
X44491Y-272838D01*
X44691D01*
X44491Y-272638D01*
X44691Y-272438D01*
X44491D01*
X44291Y-272238D01*
X44091Y-272438D01*
X43891D01*
X44091Y-272638D01*
X43891Y-272838D01*
X44091D01*
X44291Y-273038D01*
Y-327572D02*
X44691Y-327172D01*
X45091D01*
X44691Y-326772D01*
X45091Y-326372D01*
X44691D01*
X44291Y-325972D01*
X43891Y-326372D01*
X43491D01*
X43891Y-326772D01*
X43491Y-327172D01*
X43891D01*
X44291Y-327572D01*
Y-327172D02*
X44491Y-326972D01*
X44691D01*
X44491Y-326772D01*
X44691Y-326572D01*
X44491D01*
X44291Y-326372D01*
X44091Y-326572D01*
X43891D01*
X44091Y-326772D01*
X43891Y-326972D01*
X44091D01*
X44291Y-327172D01*
Y-307887D02*
X44691Y-307487D01*
X45091D01*
X44691Y-307087D01*
X45091Y-306687D01*
X44691D01*
X44291Y-306287D01*
X43891Y-306687D01*
X43491D01*
X43891Y-307087D01*
X43491Y-307487D01*
X43891D01*
X44291Y-307887D01*
Y-307487D02*
X44491Y-307287D01*
X44691D01*
X44491Y-307087D01*
X44691Y-306887D01*
X44491D01*
X44291Y-306687D01*
X44091Y-306887D01*
X43891D01*
X44091Y-307087D01*
X43891Y-307287D01*
X44091D01*
X44291Y-307487D01*
X26575Y-292139D02*
X26975Y-291739D01*
X27375D01*
X26975Y-291339D01*
X27375Y-290939D01*
X26975D01*
X26575Y-290539D01*
X26175Y-290939D01*
X25775D01*
X26175Y-291339D01*
X25775Y-291739D01*
X26175D01*
X26575Y-292139D01*
Y-291739D02*
X26775Y-291539D01*
X26975D01*
X26775Y-291339D01*
X26975Y-291139D01*
X26775D01*
X26575Y-290939D01*
X26375Y-291139D01*
X26175D01*
X26375Y-291339D01*
X26175Y-291539D01*
X26375D01*
X26575Y-291739D01*
X31496Y-190761D02*
X31896Y-190361D01*
X32296D01*
X31896Y-189961D01*
X32296Y-189561D01*
X31896D01*
X31496Y-189161D01*
X31096Y-189561D01*
X30696D01*
X31096Y-189961D01*
X30696Y-190361D01*
X31096D01*
X31496Y-190761D01*
Y-190361D02*
X31696Y-190161D01*
X31896D01*
X31696Y-189961D01*
X31896Y-189761D01*
X31696D01*
X31496Y-189561D01*
X31296Y-189761D01*
X31096D01*
X31296Y-189961D01*
X31096Y-190161D01*
X31296D01*
X31496Y-190361D01*
X44291Y-148438D02*
X44691Y-148038D01*
X45091D01*
X44691Y-147638D01*
X45091Y-147238D01*
X44691D01*
X44291Y-146838D01*
X43891Y-147238D01*
X43491D01*
X43891Y-147638D01*
X43491Y-148038D01*
X43891D01*
X44291Y-148438D01*
Y-148038D02*
X44491Y-147838D01*
X44691D01*
X44491Y-147638D01*
X44691Y-147438D01*
X44491D01*
X44291Y-147238D01*
X44091Y-147438D01*
X43891D01*
X44091Y-147638D01*
X43891Y-147838D01*
X44091D01*
X44291Y-148038D01*
Y-168123D02*
X44691Y-167723D01*
X45091D01*
X44691Y-167323D01*
X45091Y-166923D01*
X44691D01*
X44291Y-166523D01*
X43891Y-166923D01*
X43491D01*
X43891Y-167323D01*
X43491Y-167723D01*
X43891D01*
X44291Y-168123D01*
Y-167723D02*
X44491Y-167523D01*
X44691D01*
X44491Y-167323D01*
X44691Y-167123D01*
X44491D01*
X44291Y-166923D01*
X44091Y-167123D01*
X43891D01*
X44091Y-167323D01*
X43891Y-167523D01*
X44091D01*
X44291Y-167723D01*
Y-201587D02*
X44691Y-201187D01*
X45091D01*
X44691Y-200787D01*
X45091Y-200387D01*
X44691D01*
X44291Y-199987D01*
X43891Y-200387D01*
X43491D01*
X43891Y-200787D01*
X43491Y-201187D01*
X43891D01*
X44291Y-201587D01*
Y-201187D02*
X44491Y-200987D01*
X44691D01*
X44491Y-200787D01*
X44691Y-200587D01*
X44491D01*
X44291Y-200387D01*
X44091Y-200587D01*
X43891D01*
X44091Y-200787D01*
X43891Y-200987D01*
X44091D01*
X44291Y-201187D01*
Y-221272D02*
X44691Y-220872D01*
X45091D01*
X44691Y-220472D01*
X45091Y-220072D01*
X44691D01*
X44291Y-219672D01*
X43891Y-220072D01*
X43491D01*
X43891Y-220472D01*
X43491Y-220872D01*
X43891D01*
X44291Y-221272D01*
Y-220872D02*
X44491Y-220672D01*
X44691D01*
X44491Y-220472D01*
X44691Y-220272D01*
X44491D01*
X44291Y-220072D01*
X44091Y-220272D01*
X43891D01*
X44091Y-220472D01*
X43891Y-220672D01*
X44091D01*
X44291Y-220872D01*
X570727Y-106462D02*
X571128Y-106062D01*
X571527D01*
X571128Y-105662D01*
X571527Y-105262D01*
X571128D01*
X570727Y-104862D01*
X570328Y-105262D01*
X569928D01*
X570328Y-105662D01*
X569928Y-106062D01*
X570328D01*
X570727Y-106462D01*
Y-106062D02*
X570927Y-105862D01*
X571128D01*
X570927Y-105662D01*
X571128Y-105462D01*
X570927D01*
X570727Y-105262D01*
X570528Y-105462D01*
X570328D01*
X570528Y-105662D01*
X570328Y-105862D01*
X570528D01*
X570727Y-106062D01*
X325787Y-244005D02*
X326187Y-243605D01*
X326587D01*
X326187Y-243205D01*
X326587Y-242805D01*
X326187D01*
X325787Y-242405D01*
X325387Y-242805D01*
X324987D01*
X325387Y-243205D01*
X324987Y-243605D01*
X325387D01*
X325787Y-244005D01*
Y-243605D02*
X325987Y-243405D01*
X326187D01*
X325987Y-243205D01*
X326187Y-243005D01*
X325987D01*
X325787Y-242805D01*
X325587Y-243005D01*
X325387D01*
X325587Y-243205D01*
X325387Y-243405D01*
X325587D01*
X325787Y-243605D01*
Y-234162D02*
X326187Y-233762D01*
X326587D01*
X326187Y-233362D01*
X326587Y-232962D01*
X326187D01*
X325787Y-232562D01*
X325387Y-232962D01*
X324987D01*
X325387Y-233362D01*
X324987Y-233762D01*
X325387D01*
X325787Y-234162D01*
Y-233762D02*
X325987Y-233562D01*
X326187D01*
X325987Y-233362D01*
X326187Y-233162D01*
X325987D01*
X325787Y-232962D01*
X325587Y-233162D01*
X325387D01*
X325587Y-233362D01*
X325387Y-233562D01*
X325587D01*
X325787Y-233762D01*
X103409Y-142532D02*
X103809Y-142132D01*
X104209D01*
X103809Y-141732D01*
X104209Y-141332D01*
X103809D01*
X103409Y-140932D01*
X103009Y-141332D01*
X102609D01*
X103009Y-141732D01*
X102609Y-142132D01*
X103009D01*
X103409Y-142532D01*
Y-142132D02*
X103609Y-141932D01*
X103809D01*
X103609Y-141732D01*
X103809Y-141532D01*
X103609D01*
X103409Y-141332D01*
X103209Y-141532D01*
X103009D01*
X103209Y-141732D01*
X103009Y-141932D01*
X103209D01*
X103409Y-142132D01*
X103347Y-111036D02*
X103746Y-110636D01*
X104147D01*
X103746Y-110236D01*
X104147Y-109836D01*
X103746D01*
X103347Y-109436D01*
X102946Y-109836D01*
X102547D01*
X102946Y-110236D01*
X102547Y-110636D01*
X102946D01*
X103347Y-111036D01*
Y-110636D02*
X103547Y-110436D01*
X103746D01*
X103547Y-110236D01*
X103746Y-110036D01*
X103547D01*
X103347Y-109836D01*
X103147Y-110036D01*
X102946D01*
X103147Y-110236D01*
X102946Y-110436D01*
X103147D01*
X103347Y-110636D01*
X119095Y-126847D02*
X119494Y-126447D01*
X119895D01*
X119494Y-126047D01*
X119895Y-125647D01*
X119494D01*
X119095Y-125247D01*
X118694Y-125647D01*
X118295D01*
X118694Y-126047D01*
X118295Y-126447D01*
X118694D01*
X119095Y-126847D01*
Y-126447D02*
X119295Y-126247D01*
X119494D01*
X119295Y-126047D01*
X119494Y-125847D01*
X119295D01*
X119095Y-125647D01*
X118895Y-125847D01*
X118694D01*
X118895Y-126047D01*
X118694Y-126247D01*
X118895D01*
X119095Y-126447D01*
X494095Y-138447D02*
X494494Y-138047D01*
X494895D01*
X494494Y-137647D01*
X494895Y-137247D01*
X494494D01*
X494095Y-136847D01*
X493694Y-137247D01*
X493294D01*
X493694Y-137647D01*
X493294Y-138047D01*
X493694D01*
X494095Y-138447D01*
Y-138047D02*
X494295Y-137847D01*
X494494D01*
X494295Y-137647D01*
X494494Y-137447D01*
X494295D01*
X494095Y-137247D01*
X493894Y-137447D01*
X493694D01*
X493894Y-137647D01*
X493694Y-137847D01*
X493894D01*
X494095Y-138047D01*
X518701Y-105014D02*
X519101Y-104614D01*
X519501D01*
X519101Y-104214D01*
X519501Y-103814D01*
X519101D01*
X518701Y-103414D01*
X518301Y-103814D01*
X517901D01*
X518301Y-104214D01*
X517901Y-104614D01*
X518301D01*
X518701Y-105014D01*
Y-104614D02*
X518901Y-104414D01*
X519101D01*
X518901Y-104214D01*
X519101Y-104014D01*
X518901D01*
X518701Y-103814D01*
X518501Y-104014D01*
X518301D01*
X518501Y-104214D01*
X518301Y-104414D01*
X518501D01*
X518701Y-104614D01*
X519587Y-135396D02*
X519987Y-134996D01*
X520387D01*
X519987Y-134596D01*
X520387Y-134196D01*
X519987D01*
X519587Y-133796D01*
X519187Y-134196D01*
X518787D01*
X519187Y-134596D01*
X518787Y-134996D01*
X519187D01*
X519587Y-135396D01*
Y-134996D02*
X519787Y-134796D01*
X519987D01*
X519787Y-134596D01*
X519987Y-134396D01*
X519787D01*
X519587Y-134196D01*
X519387Y-134396D01*
X519187D01*
X519387Y-134596D01*
X519187Y-134796D01*
X519387D01*
X519587Y-134996D01*
X528543Y-105014D02*
X528943Y-104614D01*
X529343D01*
X528943Y-104214D01*
X529343Y-103814D01*
X528943D01*
X528543Y-103414D01*
X528143Y-103814D01*
X527743D01*
X528143Y-104214D01*
X527743Y-104614D01*
X528143D01*
X528543Y-105014D01*
Y-104614D02*
X528743Y-104414D01*
X528943D01*
X528743Y-104214D01*
X528943Y-104014D01*
X528743D01*
X528543Y-103814D01*
X528343Y-104014D01*
X528143D01*
X528343Y-104214D01*
X528143Y-104414D01*
X528343D01*
X528543Y-104614D01*
X625000Y-48880D02*
X625400Y-48480D01*
X625800D01*
X625400Y-48080D01*
X625800Y-47680D01*
X625400D01*
X625000Y-47280D01*
X624600Y-47680D01*
X624200D01*
X624600Y-48080D01*
X624200Y-48480D01*
X624600D01*
X625000Y-48880D01*
Y-48480D02*
X625200Y-48280D01*
X625400D01*
X625200Y-48080D01*
X625400Y-47880D01*
X625200D01*
X625000Y-47680D01*
X624800Y-47880D01*
X624600D01*
X624800Y-48080D01*
X624600Y-48280D01*
X624800D01*
X625000Y-48480D01*
X658465Y-22699D02*
X658865Y-22299D01*
X659265D01*
X658865Y-21899D01*
X659265Y-21499D01*
X658865D01*
X658465Y-21099D01*
X658065Y-21499D01*
X657665D01*
X658065Y-21899D01*
X657665Y-22299D01*
X658065D01*
X658465Y-22699D01*
Y-22299D02*
X658665Y-22099D01*
X658865D01*
X658665Y-21899D01*
X658865Y-21699D01*
X658665D01*
X658465Y-21499D01*
X658265Y-21699D01*
X658065D01*
X658265Y-21899D01*
X658065Y-22099D01*
X658265D01*
X658465Y-22299D01*
X625000Y-30573D02*
X625400Y-30173D01*
X625800D01*
X625400Y-29773D01*
X625800Y-29373D01*
X625400D01*
X625000Y-28973D01*
X624600Y-29373D01*
X624200D01*
X624600Y-29773D01*
X624200Y-30173D01*
X624600D01*
X625000Y-30573D01*
Y-30173D02*
X625200Y-29973D01*
X625400D01*
X625200Y-29773D01*
X625400Y-29573D01*
X625200D01*
X625000Y-29373D01*
X624800Y-29573D01*
X624600D01*
X624800Y-29773D01*
X624600Y-29973D01*
X624800D01*
X625000Y-30173D01*
X114173Y-83888D02*
X114573Y-83488D01*
X114973D01*
X114573Y-83088D01*
X114973Y-82688D01*
X114573D01*
X114173Y-82288D01*
X113773Y-82688D01*
X113373D01*
X113773Y-83088D01*
X113373Y-83488D01*
X113773D01*
X114173Y-83888D01*
Y-83488D02*
X114373Y-83288D01*
X114573D01*
X114373Y-83088D01*
X114573Y-82888D01*
X114373D01*
X114173Y-82688D01*
X113973Y-82888D01*
X113773D01*
X113973Y-83088D01*
X113773Y-83288D01*
X113973D01*
X114173Y-83488D01*
X441929Y-123684D02*
X442329Y-123284D01*
X442729D01*
X442329Y-122883D01*
X442729Y-122484D01*
X442329D01*
X441929Y-122083D01*
X441529Y-122484D01*
X441129D01*
X441529Y-122883D01*
X441129Y-123284D01*
X441529D01*
X441929Y-123684D01*
Y-123284D02*
X442129Y-123083D01*
X442329D01*
X442129Y-122883D01*
X442329Y-122684D01*
X442129D01*
X441929Y-122484D01*
X441729Y-122684D01*
X441529D01*
X441729Y-122883D01*
X441529Y-123083D01*
X441729D01*
X441929Y-123284D01*
X256890Y-125652D02*
X257290Y-125252D01*
X257690D01*
X257290Y-124852D01*
X257690Y-124452D01*
X257290D01*
X256890Y-124052D01*
X256490Y-124452D01*
X256090D01*
X256490Y-124852D01*
X256090Y-125252D01*
X256490D01*
X256890Y-125652D01*
Y-125252D02*
X257090Y-125052D01*
X257290D01*
X257090Y-124852D01*
X257290Y-124652D01*
X257090D01*
X256890Y-124452D01*
X256690Y-124652D01*
X256490D01*
X256690Y-124852D01*
X256490Y-125052D01*
X256690D01*
X256890Y-125252D01*
Y-122699D02*
X257290Y-122299D01*
X257690D01*
X257290Y-121899D01*
X257690Y-121499D01*
X257290D01*
X256890Y-121099D01*
X256490Y-121499D01*
X256090D01*
X256490Y-121899D01*
X256090Y-122299D01*
X256490D01*
X256890Y-122699D01*
Y-122299D02*
X257090Y-122099D01*
X257290D01*
X257090Y-121899D01*
X257290Y-121699D01*
X257090D01*
X256890Y-121499D01*
X256690Y-121699D01*
X256490D01*
X256690Y-121899D01*
X256490Y-122099D01*
X256690D01*
X256890Y-122299D01*
X250000Y-121715D02*
X250400Y-121315D01*
X250800D01*
X250400Y-120915D01*
X250800Y-120515D01*
X250400D01*
X250000Y-120115D01*
X249600Y-120515D01*
X249200D01*
X249600Y-120915D01*
X249200Y-121315D01*
X249600D01*
X250000Y-121715D01*
Y-121315D02*
X250200Y-121115D01*
X250400D01*
X250200Y-120915D01*
X250400Y-120715D01*
X250200D01*
X250000Y-120515D01*
X249800Y-120715D01*
X249600D01*
X249800Y-120915D01*
X249600Y-121115D01*
X249800D01*
X250000Y-121315D01*
X129921Y-80376D02*
X130321Y-79976D01*
X130721D01*
X130321Y-79576D01*
X130721Y-79176D01*
X130321D01*
X129921Y-78776D01*
X129521Y-79176D01*
X129121D01*
X129521Y-79576D01*
X129121Y-79976D01*
X129521D01*
X129921Y-80376D01*
Y-79976D02*
X130121Y-79776D01*
X130321D01*
X130121Y-79576D01*
X130321Y-79376D01*
X130121D01*
X129921Y-79176D01*
X129721Y-79376D01*
X129521D01*
X129721Y-79576D01*
X129521Y-79776D01*
X129721D01*
X129921Y-79976D01*
X473425Y-126636D02*
X473825Y-126236D01*
X474225D01*
X473825Y-125836D01*
X474225Y-125436D01*
X473825D01*
X473425Y-125036D01*
X473025Y-125436D01*
X472625D01*
X473025Y-125836D01*
X472625Y-126236D01*
X473025D01*
X473425Y-126636D01*
Y-126236D02*
X473625Y-126036D01*
X473825D01*
X473625Y-125836D01*
X473825Y-125636D01*
X473625D01*
X473425Y-125436D01*
X473225Y-125636D01*
X473025D01*
X473225Y-125836D01*
X473025Y-126036D01*
X473225D01*
X473425Y-126236D01*
X473425Y-124668D02*
X473825Y-124268D01*
X474225D01*
X473825Y-123868D01*
X474225Y-123468D01*
X473825D01*
X473425Y-123068D01*
X473025Y-123468D01*
X472625D01*
X473025Y-123868D01*
X472625Y-124268D01*
X473025D01*
X473425Y-124668D01*
Y-124268D02*
X473625Y-124068D01*
X473825D01*
X473625Y-123868D01*
X473825Y-123668D01*
X473625D01*
X473425Y-123468D01*
X473225Y-123668D01*
X473025D01*
X473225Y-123868D01*
X473025Y-124068D01*
X473225D01*
X473425Y-124268D01*
X473425Y-122699D02*
X473825Y-122299D01*
X474225D01*
X473825Y-121899D01*
X474225Y-121499D01*
X473825D01*
X473425Y-121099D01*
X473025Y-121499D01*
X472625D01*
X473025Y-121899D01*
X472625Y-122299D01*
X473025D01*
X473425Y-122699D01*
Y-122299D02*
X473625Y-122099D01*
X473825D01*
X473625Y-121899D01*
X473825Y-121699D01*
X473625D01*
X473425Y-121499D01*
X473225Y-121699D01*
X473025D01*
X473225Y-121899D01*
X473025Y-122099D01*
X473225D01*
X473425Y-122299D01*
X505905Y-138447D02*
X506306Y-138047D01*
X506706D01*
X506306Y-137647D01*
X506706Y-137247D01*
X506306D01*
X505905Y-136847D01*
X505506Y-137247D01*
X505105D01*
X505506Y-137647D01*
X505105Y-138047D01*
X505506D01*
X505905Y-138447D01*
Y-138047D02*
X506106Y-137847D01*
X506306D01*
X506106Y-137647D01*
X506306Y-137447D01*
X506106D01*
X505905Y-137247D01*
X505705Y-137447D01*
X505506D01*
X505705Y-137647D01*
X505506Y-137847D01*
X505705D01*
X505905Y-138047D01*
X163071Y-391530D02*
X163471Y-391130D01*
X163871D01*
X163471Y-390730D01*
X163871Y-390330D01*
X163471D01*
X163071Y-389930D01*
X162671Y-390330D01*
X162271D01*
X162671Y-390730D01*
X162271Y-391130D01*
X162671D01*
X163071Y-391530D01*
Y-391130D02*
X163271Y-390930D01*
X163471D01*
X163271Y-390730D01*
X163471Y-390530D01*
X163271D01*
X163071Y-390330D01*
X162871Y-390530D01*
X162671D01*
X162871Y-390730D01*
X162671Y-390930D01*
X162871D01*
X163071Y-391130D01*
X632432Y-133280D02*
X632831Y-132880D01*
X633231D01*
X632831Y-132480D01*
X633231Y-132080D01*
X632831D01*
X632432Y-131680D01*
X632031Y-132080D01*
X631632D01*
X632031Y-132480D01*
X631632Y-132880D01*
X632031D01*
X632432Y-133280D01*
Y-132880D02*
X632631Y-132680D01*
X632831D01*
X632631Y-132480D01*
X632831Y-132280D01*
X632631D01*
X632432Y-132080D01*
X632232Y-132280D01*
X632031D01*
X632232Y-132480D01*
X632031Y-132680D01*
X632232D01*
X632432Y-132880D01*
X614321Y-119107D02*
X614721Y-118707D01*
X615121D01*
X614721Y-118307D01*
X615121Y-117907D01*
X614721D01*
X614321Y-117507D01*
X613921Y-117907D01*
X613521D01*
X613921Y-118307D01*
X613521Y-118707D01*
X613921D01*
X614321Y-119107D01*
Y-118707D02*
X614521Y-118507D01*
X614721D01*
X614521Y-118307D01*
X614721Y-118107D01*
X614521D01*
X614321Y-117907D01*
X614121Y-118107D01*
X613921D01*
X614121Y-118307D01*
X613921Y-118507D01*
X614121D01*
X614321Y-118707D01*
X99410Y-50849D02*
X99809Y-50449D01*
X100209D01*
X99809Y-50049D01*
X100209Y-49649D01*
X99809D01*
X99410Y-49249D01*
X99010Y-49649D01*
X98610D01*
X99010Y-50049D01*
X98610Y-50449D01*
X99010D01*
X99410Y-50849D01*
Y-50449D02*
X99610Y-50249D01*
X99809D01*
X99610Y-50049D01*
X99809Y-49849D01*
X99610D01*
X99410Y-49649D01*
X99209Y-49849D01*
X99010D01*
X99209Y-50049D01*
X99010Y-50249D01*
X99209D01*
X99410Y-50449D01*
X26495Y-9791D02*
X26895Y-9391D01*
X27295D01*
X26895Y-8991D01*
X27295Y-8591D01*
X26895D01*
X26495Y-8191D01*
X26095Y-8591D01*
X25695D01*
X26095Y-8991D01*
X25695Y-9391D01*
X26095D01*
X26495Y-9791D01*
Y-9391D02*
X26695Y-9191D01*
X26895D01*
X26695Y-8991D01*
X26895Y-8791D01*
X26695D01*
X26495Y-8591D01*
X26295Y-8791D01*
X26095D01*
X26295Y-8991D01*
X26095Y-9191D01*
X26295D01*
X26495Y-9391D01*
X512657Y-271262D02*
X513057Y-270862D01*
X513457D01*
X513057Y-270462D01*
X513457Y-270062D01*
X513057D01*
X512657Y-269662D01*
X512257Y-270062D01*
X511857D01*
X512257Y-270462D01*
X511857Y-270862D01*
X512257D01*
X512657Y-271262D01*
Y-270862D02*
X512857Y-270662D01*
X513057D01*
X512857Y-270462D01*
X513057Y-270262D01*
X512857D01*
X512657Y-270062D01*
X512457Y-270262D01*
X512257D01*
X512457Y-270462D01*
X512257Y-270662D01*
X512457D01*
X512657Y-270862D01*
X632432Y-141942D02*
X632831Y-141542D01*
X633231D01*
X632831Y-141142D01*
X633231Y-140742D01*
X632831D01*
X632432Y-140342D01*
X632031Y-140742D01*
X631632D01*
X632031Y-141142D01*
X631632Y-141542D01*
X632031D01*
X632432Y-141942D01*
Y-141542D02*
X632631Y-141342D01*
X632831D01*
X632631Y-141142D01*
X632831Y-140942D01*
X632631D01*
X632432Y-140742D01*
X632232Y-140942D01*
X632031D01*
X632232Y-141142D01*
X632031Y-141342D01*
X632232D01*
X632432Y-141542D01*
X259285Y-391047D02*
X259685Y-390647D01*
X260085D01*
X259685Y-390247D01*
X260085Y-389847D01*
X259685D01*
X259285Y-389447D01*
X258885Y-389847D01*
X258485D01*
X258885Y-390247D01*
X258485Y-390647D01*
X258885D01*
X259285Y-391047D01*
Y-390647D02*
X259485Y-390447D01*
X259685D01*
X259485Y-390247D01*
X259685Y-390047D01*
X259485D01*
X259285Y-389847D01*
X259085Y-390047D01*
X258885D01*
X259085Y-390247D01*
X258885Y-390447D01*
X259085D01*
X259285Y-390647D01*
X267204Y-390809D02*
X267604Y-390409D01*
X268004D01*
X267604Y-390009D01*
X268004Y-389610D01*
X267604D01*
X267204Y-389210D01*
X266804Y-389610D01*
X266404D01*
X266804Y-390009D01*
X266404Y-390409D01*
X266804D01*
X267204Y-390809D01*
Y-390409D02*
X267404Y-390210D01*
X267604D01*
X267404Y-390009D01*
X267604Y-389809D01*
X267404D01*
X267204Y-389610D01*
X267004Y-389809D01*
X266804D01*
X267004Y-390009D01*
X266804Y-390210D01*
X267004D01*
X267204Y-390409D01*
X216162Y-391747D02*
X216562Y-391347D01*
X216962D01*
X216562Y-390947D01*
X216962Y-390547D01*
X216562D01*
X216162Y-390147D01*
X215762Y-390547D01*
X215362D01*
X215762Y-390947D01*
X215362Y-391347D01*
X215762D01*
X216162Y-391747D01*
Y-391347D02*
X216362Y-391147D01*
X216562D01*
X216362Y-390947D01*
X216562Y-390747D01*
X216362D01*
X216162Y-390547D01*
X215962Y-390747D01*
X215762D01*
X215962Y-390947D01*
X215762Y-391147D01*
X215962D01*
X216162Y-391347D01*
X235144Y-391216D02*
X235544Y-390816D01*
X235944D01*
X235544Y-390416D01*
X235944Y-390016D01*
X235544D01*
X235144Y-389616D01*
X234744Y-390016D01*
X234344D01*
X234744Y-390416D01*
X234344Y-390816D01*
X234744D01*
X235144Y-391216D01*
Y-390816D02*
X235344Y-390616D01*
X235544D01*
X235344Y-390416D01*
X235544Y-390216D01*
X235344D01*
X235144Y-390016D01*
X234944Y-390216D01*
X234744D01*
X234944Y-390416D01*
X234744Y-390616D01*
X234944D01*
X235144Y-390816D01*
X251456Y-390809D02*
X251856Y-390409D01*
X252256D01*
X251856Y-390009D01*
X252256Y-389610D01*
X251856D01*
X251456Y-389210D01*
X251056Y-389610D01*
X250656D01*
X251056Y-390009D01*
X250656Y-390409D01*
X251056D01*
X251456Y-390809D01*
Y-390409D02*
X251656Y-390210D01*
X251856D01*
X251656Y-390009D01*
X251856Y-389809D01*
X251656D01*
X251456Y-389610D01*
X251256Y-389809D01*
X251056D01*
X251256Y-390009D01*
X251056Y-390210D01*
X251256D01*
X251456Y-390409D01*
X226063Y-391522D02*
X226463Y-391122D01*
X226863D01*
X226463Y-390722D01*
X226863Y-390322D01*
X226463D01*
X226063Y-389922D01*
X225663Y-390322D01*
X225263D01*
X225663Y-390722D01*
X225263Y-391122D01*
X225663D01*
X226063Y-391522D01*
Y-391122D02*
X226263Y-390922D01*
X226463D01*
X226263Y-390722D01*
X226463Y-390522D01*
X226263D01*
X226063Y-390322D01*
X225863Y-390522D01*
X225663D01*
X225863Y-390722D01*
X225663Y-390922D01*
X225863D01*
X226063Y-391122D01*
X281201Y-390809D02*
X281601Y-390409D01*
X282001D01*
X281601Y-390009D01*
X282001Y-389610D01*
X281601D01*
X281201Y-389210D01*
X280801Y-389610D01*
X280401D01*
X280801Y-390009D01*
X280401Y-390409D01*
X280801D01*
X281201Y-390809D01*
Y-390409D02*
X281401Y-390210D01*
X281601D01*
X281401Y-390009D01*
X281601Y-389809D01*
X281401D01*
X281201Y-389610D01*
X281001Y-389809D01*
X280801D01*
X281001Y-390009D01*
X280801Y-390210D01*
X281001D01*
X281201Y-390409D01*
X174941Y-391400D02*
X175341Y-391000D01*
X175741D01*
X175341Y-390600D01*
X175741Y-390200D01*
X175341D01*
X174941Y-389800D01*
X174541Y-390200D01*
X174141D01*
X174541Y-390600D01*
X174141Y-391000D01*
X174541D01*
X174941Y-391400D01*
Y-391000D02*
X175141Y-390800D01*
X175341D01*
X175141Y-390600D01*
X175341Y-390400D01*
X175141D01*
X174941Y-390200D01*
X174741Y-390400D01*
X174541D01*
X174741Y-390600D01*
X174541Y-390800D01*
X174741D01*
X174941Y-391000D01*
X202441Y-391400D02*
X202841Y-391000D01*
X203241D01*
X202841Y-390600D01*
X203241Y-390200D01*
X202841D01*
X202441Y-389800D01*
X202041Y-390200D01*
X201641D01*
X202041Y-390600D01*
X201641Y-391000D01*
X202041D01*
X202441Y-391400D01*
Y-391000D02*
X202641Y-390800D01*
X202841D01*
X202641Y-390600D01*
X202841Y-390400D01*
X202641D01*
X202441Y-390200D01*
X202241Y-390400D01*
X202041D01*
X202241Y-390600D01*
X202041Y-390800D01*
X202241D01*
X202441Y-391000D01*
X538813Y-145306D02*
X539213Y-144905D01*
X539613D01*
X539213Y-144506D01*
X539613Y-144106D01*
X539213D01*
X538813Y-143705D01*
X538413Y-144106D01*
X538013D01*
X538413Y-144506D01*
X538013Y-144905D01*
X538413D01*
X538813Y-145306D01*
Y-144905D02*
X539013Y-144705D01*
X539213D01*
X539013Y-144506D01*
X539213Y-144306D01*
X539013D01*
X538813Y-144106D01*
X538613Y-144306D01*
X538413D01*
X538613Y-144506D01*
X538413Y-144705D01*
X538613D01*
X538813Y-144905D01*
X544813Y-110606D02*
X545213Y-110205D01*
X545613D01*
X545213Y-109806D01*
X545613Y-109406D01*
X545213D01*
X544813Y-109005D01*
X544413Y-109406D01*
X544013D01*
X544413Y-109806D01*
X544013Y-110205D01*
X544413D01*
X544813Y-110606D01*
Y-110205D02*
X545013Y-110005D01*
X545213D01*
X545013Y-109806D01*
X545213Y-109606D01*
X545013D01*
X544813Y-109406D01*
X544613Y-109606D01*
X544413D01*
X544613Y-109806D01*
X544413Y-110005D01*
X544613D01*
X544813Y-110205D01*
X566813Y-133205D02*
X567213Y-132806D01*
X567613D01*
X567213Y-132405D01*
X567613Y-132006D01*
X567213D01*
X566813Y-131606D01*
X566413Y-132006D01*
X566013D01*
X566413Y-132405D01*
X566013Y-132806D01*
X566413D01*
X566813Y-133205D01*
Y-132806D02*
X567013Y-132606D01*
X567213D01*
X567013Y-132405D01*
X567213Y-132205D01*
X567013D01*
X566813Y-132006D01*
X566613Y-132205D01*
X566413D01*
X566613Y-132405D01*
X566413Y-132606D01*
X566613D01*
X566813Y-132806D01*
X598265Y-223832D02*
X598665Y-223031D01*
X598265Y-222232D01*
X599065Y-222632D01*
X599865Y-222232D01*
X599465Y-223031D01*
X599865Y-223832D01*
X599065Y-223431D01*
X598265Y-223832D01*
X598665Y-223431D02*
X598865Y-223031D01*
X598665Y-222632D01*
X599065Y-222832D01*
X599465Y-222632D01*
X599265Y-223031D01*
X599465Y-223431D01*
X599065Y-223232D01*
X598665Y-223431D01*
X555364Y-250209D02*
X555764Y-249810D01*
X556164D01*
X555764Y-249410D01*
X556164Y-249009D01*
X555764D01*
X555364Y-248609D01*
X554964Y-249009D01*
X554564D01*
X554964Y-249410D01*
X554564Y-249810D01*
X554964D01*
X555364Y-250209D01*
Y-249810D02*
X555564Y-249609D01*
X555764D01*
X555564Y-249410D01*
X555764Y-249209D01*
X555564D01*
X555364Y-249009D01*
X555164Y-249209D01*
X554964D01*
X555164Y-249410D01*
X554964Y-249609D01*
X555164D01*
X555364Y-249810D01*
X544291Y-200455D02*
X544691Y-200055D01*
X545091D01*
X544691Y-199655D01*
X545091Y-199255D01*
X544691D01*
X544291Y-198855D01*
X543891Y-199255D01*
X543491D01*
X543891Y-199655D01*
X543491Y-200055D01*
X543891D01*
X544291Y-200455D01*
Y-200055D02*
X544491Y-199855D01*
X544691D01*
X544491Y-199655D01*
X544691Y-199455D01*
X544491D01*
X544291Y-199255D01*
X544091Y-199455D01*
X543891D01*
X544091Y-199655D01*
X543891Y-199855D01*
X544091D01*
X544291Y-200055D01*
X509842Y-198487D02*
X510243Y-198087D01*
X510642D01*
X510243Y-197687D01*
X510642Y-197287D01*
X510243D01*
X509842Y-196887D01*
X509443Y-197287D01*
X509043D01*
X509443Y-197687D01*
X509043Y-198087D01*
X509443D01*
X509842Y-198487D01*
Y-198087D02*
X510042Y-197887D01*
X510243D01*
X510042Y-197687D01*
X510243Y-197487D01*
X510042D01*
X509842Y-197287D01*
X509643Y-197487D01*
X509443D01*
X509643Y-197687D01*
X509443Y-197887D01*
X509643D01*
X509842Y-198087D01*
X544291Y-202424D02*
X544691Y-202024D01*
X545091D01*
X544691Y-201624D01*
X545091Y-201224D01*
X544691D01*
X544291Y-200824D01*
X543891Y-201224D01*
X543491D01*
X543891Y-201624D01*
X543491Y-202024D01*
X543891D01*
X544291Y-202424D01*
Y-202024D02*
X544491Y-201824D01*
X544691D01*
X544491Y-201624D01*
X544691Y-201424D01*
X544491D01*
X544291Y-201224D01*
X544091Y-201424D01*
X543891D01*
X544091Y-201624D01*
X543891Y-201824D01*
X544091D01*
X544291Y-202024D01*
X509842Y-200455D02*
X510243Y-200055D01*
X510642D01*
X510243Y-199655D01*
X510642Y-199255D01*
X510243D01*
X509842Y-198855D01*
X509443Y-199255D01*
X509043D01*
X509443Y-199655D01*
X509043Y-200055D01*
X509443D01*
X509842Y-200455D01*
Y-200055D02*
X510042Y-199855D01*
X510243D01*
X510042Y-199655D01*
X510243Y-199455D01*
X510042D01*
X509842Y-199255D01*
X509643Y-199455D01*
X509443D01*
X509643Y-199655D01*
X509443Y-199855D01*
X509643D01*
X509842Y-200055D01*
Y-202424D02*
X510243Y-202024D01*
X510642D01*
X510243Y-201624D01*
X510642Y-201224D01*
X510243D01*
X509842Y-200824D01*
X509443Y-201224D01*
X509043D01*
X509443Y-201624D01*
X509043Y-202024D01*
X509443D01*
X509842Y-202424D01*
Y-202024D02*
X510042Y-201824D01*
X510243D01*
X510042Y-201624D01*
X510243Y-201424D01*
X510042D01*
X509842Y-201224D01*
X509643Y-201424D01*
X509443D01*
X509643Y-201624D01*
X509443Y-201824D01*
X509643D01*
X509842Y-202024D01*
X544291Y-198487D02*
X544691Y-198087D01*
X545091D01*
X544691Y-197687D01*
X545091Y-197287D01*
X544691D01*
X544291Y-196887D01*
X543891Y-197287D01*
X543491D01*
X543891Y-197687D01*
X543491Y-198087D01*
X543891D01*
X544291Y-198487D01*
Y-198087D02*
X544491Y-197887D01*
X544691D01*
X544491Y-197687D01*
X544691Y-197487D01*
X544491D01*
X544291Y-197287D01*
X544091Y-197487D01*
X543891D01*
X544091Y-197687D01*
X543891Y-197887D01*
X544091D01*
X544291Y-198087D01*
X509842Y-196518D02*
X510243Y-196118D01*
X510642D01*
X510243Y-195718D01*
X510642Y-195318D01*
X510243D01*
X509842Y-194918D01*
X509443Y-195318D01*
X509043D01*
X509443Y-195718D01*
X509043Y-196118D01*
X509443D01*
X509842Y-196518D01*
Y-196118D02*
X510042Y-195918D01*
X510243D01*
X510042Y-195718D01*
X510243Y-195518D01*
X510042D01*
X509842Y-195318D01*
X509643Y-195518D01*
X509443D01*
X509643Y-195718D01*
X509443Y-195918D01*
X509643D01*
X509842Y-196118D01*
X361811Y-207887D02*
X362211Y-207487D01*
X362611D01*
X362211Y-207087D01*
X362611Y-206687D01*
X362211D01*
X361811Y-206287D01*
X361411Y-206687D01*
X361011D01*
X361411Y-207087D01*
X361011Y-207487D01*
X361411D01*
X361811Y-207887D01*
Y-207487D02*
X362011Y-207287D01*
X362211D01*
X362011Y-207087D01*
X362211Y-206887D01*
X362011D01*
X361811Y-206687D01*
X361611Y-206887D01*
X361411D01*
X361611Y-207087D01*
X361411Y-207287D01*
X361611D01*
X361811Y-207487D01*
X361417Y-203950D02*
X361817Y-203550D01*
X362217D01*
X361817Y-203150D01*
X362217Y-202750D01*
X361817D01*
X361417Y-202350D01*
X361017Y-202750D01*
X360617D01*
X361017Y-203150D01*
X360617Y-203550D01*
X361017D01*
X361417Y-203950D01*
Y-203550D02*
X361617Y-203350D01*
X361817D01*
X361617Y-203150D01*
X361817Y-202950D01*
X361617D01*
X361417Y-202750D01*
X361217Y-202950D01*
X361017D01*
X361217Y-203150D01*
X361017Y-203350D01*
X361217D01*
X361417Y-203550D01*
X326969Y-198373D02*
X327368Y-197973D01*
X327768D01*
X327368Y-197573D01*
X327768Y-197173D01*
X327368D01*
X326969Y-196773D01*
X326569Y-197173D01*
X326168D01*
X326569Y-197573D01*
X326168Y-197973D01*
X326569D01*
X326969Y-198373D01*
Y-197973D02*
X327168Y-197773D01*
X327368D01*
X327168Y-197573D01*
X327368Y-197373D01*
X327168D01*
X326969Y-197173D01*
X326768Y-197373D01*
X326569D01*
X326768Y-197573D01*
X326569Y-197773D01*
X326768D01*
X326969Y-197973D01*
X326966Y-195971D02*
X327366Y-195571D01*
X327766D01*
X327366Y-195171D01*
X327766Y-194771D01*
X327366D01*
X326966Y-194371D01*
X326566Y-194771D01*
X326166D01*
X326566Y-195171D01*
X326166Y-195571D01*
X326566D01*
X326966Y-195971D01*
Y-195571D02*
X327166Y-195371D01*
X327366D01*
X327166Y-195171D01*
X327366Y-194971D01*
X327166D01*
X326966Y-194771D01*
X326766Y-194971D01*
X326566D01*
X326766Y-195171D01*
X326566Y-195371D01*
X326766D01*
X326966Y-195571D01*
X366535Y-203162D02*
X366935Y-202762D01*
X367335D01*
X366935Y-202362D01*
X367335Y-201962D01*
X366935D01*
X366535Y-201562D01*
X366135Y-201962D01*
X365735D01*
X366135Y-202362D01*
X365735Y-202762D01*
X366135D01*
X366535Y-203162D01*
Y-202762D02*
X366735Y-202562D01*
X366935D01*
X366735Y-202362D01*
X366935Y-202162D01*
X366735D01*
X366535Y-201962D01*
X366335Y-202162D01*
X366135D01*
X366335Y-202362D01*
X366135Y-202562D01*
X366335D01*
X366535Y-202762D01*
X358661Y-195288D02*
X359061Y-194888D01*
X359461D01*
X359061Y-194488D01*
X359461Y-194088D01*
X359061D01*
X358661Y-193688D01*
X358261Y-194088D01*
X357861D01*
X358261Y-194488D01*
X357861Y-194888D01*
X358261D01*
X358661Y-195288D01*
Y-194888D02*
X358861Y-194688D01*
X359061D01*
X358861Y-194488D01*
X359061Y-194288D01*
X358861D01*
X358661Y-194088D01*
X358461Y-194288D01*
X358261D01*
X358461Y-194488D01*
X358261Y-194688D01*
X358461D01*
X358661Y-194888D01*
X634252Y-315367D02*
X634652Y-314967D01*
X635052D01*
X634652Y-314567D01*
X635052Y-314167D01*
X634652D01*
X634252Y-313767D01*
X633852Y-314167D01*
X633452D01*
X633852Y-314567D01*
X633452Y-314967D01*
X633852D01*
X634252Y-315367D01*
Y-314967D02*
X634452Y-314767D01*
X634652D01*
X634452Y-314567D01*
X634652Y-314367D01*
X634452D01*
X634252Y-314167D01*
X634052Y-314367D01*
X633852D01*
X634052Y-314567D01*
X633852Y-314767D01*
X634052D01*
X634252Y-314967D01*
X653150Y-315367D02*
X653550Y-314967D01*
X653950D01*
X653550Y-314567D01*
X653950Y-314167D01*
X653550D01*
X653150Y-313767D01*
X652750Y-314167D01*
X652350D01*
X652750Y-314567D01*
X652350Y-314967D01*
X652750D01*
X653150Y-315367D01*
Y-314967D02*
X653350Y-314767D01*
X653550D01*
X653350Y-314567D01*
X653550Y-314367D01*
X653350D01*
X653150Y-314167D01*
X652950Y-314367D01*
X652750D01*
X652950Y-314567D01*
X652750Y-314767D01*
X652950D01*
X653150Y-314967D01*
X509391Y-351436D02*
X509791Y-351036D01*
X510191D01*
X509791Y-350636D01*
X510191Y-350236D01*
X509791D01*
X509391Y-349836D01*
X508991Y-350236D01*
X508591D01*
X508991Y-350636D01*
X508591Y-351036D01*
X508991D01*
X509391Y-351436D01*
Y-351036D02*
X509591Y-350836D01*
X509791D01*
X509591Y-350636D01*
X509791Y-350436D01*
X509591D01*
X509391Y-350236D01*
X509191Y-350436D01*
X508991D01*
X509191Y-350636D01*
X508991Y-350836D01*
X509191D01*
X509391Y-351036D01*
X508997Y-336475D02*
X509397Y-336075D01*
X509797D01*
X509397Y-335675D01*
X509797Y-335275D01*
X509397D01*
X508997Y-334875D01*
X508597Y-335275D01*
X508197D01*
X508597Y-335675D01*
X508197Y-336075D01*
X508597D01*
X508997Y-336475D01*
Y-336075D02*
X509197Y-335875D01*
X509397D01*
X509197Y-335675D01*
X509397Y-335475D01*
X509197D01*
X508997Y-335275D01*
X508797Y-335475D01*
X508597D01*
X508797Y-335675D01*
X508597Y-335875D01*
X508797D01*
X508997Y-336075D01*
X237402Y-134265D02*
X237802Y-133865D01*
X238202D01*
X237802Y-133465D01*
X238202Y-133065D01*
X237802D01*
X237402Y-132665D01*
X237002Y-133065D01*
X236602D01*
X237002Y-133465D01*
X236602Y-133865D01*
X237002D01*
X237402Y-134265D01*
Y-133865D02*
X237602Y-133665D01*
X237802D01*
X237602Y-133465D01*
X237802Y-133265D01*
X237602D01*
X237402Y-133065D01*
X237202Y-133265D01*
X237002D01*
X237202Y-133465D01*
X237002Y-133665D01*
X237202D01*
X237402Y-133865D01*
X240945Y-134265D02*
X241345Y-133865D01*
X241745D01*
X241345Y-133465D01*
X241745Y-133065D01*
X241345D01*
X240945Y-132665D01*
X240545Y-133065D01*
X240145D01*
X240545Y-133465D01*
X240145Y-133865D01*
X240545D01*
X240945Y-134265D01*
Y-133865D02*
X241145Y-133665D01*
X241345D01*
X241145Y-133465D01*
X241345Y-133265D01*
X241145D01*
X240945Y-133065D01*
X240745Y-133265D01*
X240545D01*
X240745Y-133465D01*
X240545Y-133665D01*
X240745D01*
X240945Y-133865D01*
X685039Y0D02*
Y1333D01*
X685706Y1999D01*
X686372Y1333D01*
Y0D01*
Y1000D01*
X685039D01*
X685039Y-340551D02*
Y-339218D01*
X685706Y-338552D01*
X686372Y-339218D01*
Y-340551D01*
Y-339551D01*
X685039D01*
X447244Y-325652D02*
X447644Y-325252D01*
X448044D01*
X447644Y-324852D01*
X448044Y-324452D01*
X447644D01*
X447244Y-324052D01*
X446844Y-324452D01*
X446444D01*
X446844Y-324852D01*
X446444Y-325252D01*
X446844D01*
X447244Y-325652D01*
Y-325252D02*
X447444Y-325052D01*
X447644D01*
X447444Y-324852D01*
X447644Y-324652D01*
X447444D01*
X447244Y-324452D01*
X447044Y-324652D01*
X446844D01*
X447044Y-324852D01*
X446844Y-325052D01*
X447044D01*
X447244Y-325252D01*
X451181Y-325652D02*
X451581Y-325252D01*
X451981D01*
X451581Y-324852D01*
X451981Y-324452D01*
X451581D01*
X451181Y-324052D01*
X450781Y-324452D01*
X450381D01*
X450781Y-324852D01*
X450381Y-325252D01*
X450781D01*
X451181Y-325652D01*
Y-325252D02*
X451381Y-325052D01*
X451581D01*
X451381Y-324852D01*
X451581Y-324652D01*
X451381D01*
X451181Y-324452D01*
X450981Y-324652D01*
X450781D01*
X450981Y-324852D01*
X450781Y-325052D01*
X450981D01*
X451181Y-325252D01*
X433858Y-325652D02*
X434258Y-325252D01*
X434658D01*
X434258Y-324852D01*
X434658Y-324452D01*
X434258D01*
X433858Y-324052D01*
X433458Y-324452D01*
X433058D01*
X433458Y-324852D01*
X433058Y-325252D01*
X433458D01*
X433858Y-325652D01*
Y-325252D02*
X434058Y-325052D01*
X434258D01*
X434058Y-324852D01*
X434258Y-324652D01*
X434058D01*
X433858Y-324452D01*
X433658Y-324652D01*
X433458D01*
X433658Y-324852D01*
X433458Y-325052D01*
X433658D01*
X433858Y-325252D01*
X460630Y-325652D02*
X461030Y-325252D01*
X461430D01*
X461030Y-324852D01*
X461430Y-324452D01*
X461030D01*
X460630Y-324052D01*
X460230Y-324452D01*
X459830D01*
X460230Y-324852D01*
X459830Y-325252D01*
X460230D01*
X460630Y-325652D01*
Y-325252D02*
X460830Y-325052D01*
X461030D01*
X460830Y-324852D01*
X461030Y-324652D01*
X460830D01*
X460630Y-324452D01*
X460430Y-324652D01*
X460230D01*
X460430Y-324852D01*
X460230Y-325052D01*
X460430D01*
X460630Y-325252D01*
X437795Y-325652D02*
X438195Y-325252D01*
X438595D01*
X438195Y-324852D01*
X438595Y-324452D01*
X438195D01*
X437795Y-324052D01*
X437395Y-324452D01*
X436995D01*
X437395Y-324852D01*
X436995Y-325252D01*
X437395D01*
X437795Y-325652D01*
Y-325252D02*
X437995Y-325052D01*
X438195D01*
X437995Y-324852D01*
X438195Y-324652D01*
X437995D01*
X437795Y-324452D01*
X437595Y-324652D01*
X437395D01*
X437595Y-324852D01*
X437395Y-325052D01*
X437595D01*
X437795Y-325252D01*
X431102Y-325652D02*
X431502Y-325252D01*
X431902D01*
X431502Y-324852D01*
X431902Y-324452D01*
X431502D01*
X431102Y-324052D01*
X430702Y-324452D01*
X430302D01*
X430702Y-324852D01*
X430302Y-325252D01*
X430702D01*
X431102Y-325652D01*
Y-325252D02*
X431302Y-325052D01*
X431502D01*
X431302Y-324852D01*
X431502Y-324652D01*
X431302D01*
X431102Y-324452D01*
X430902Y-324652D01*
X430702D01*
X430902Y-324852D01*
X430702Y-325052D01*
X430902D01*
X431102Y-325252D01*
X444488Y-325652D02*
X444888Y-325252D01*
X445288D01*
X444888Y-324852D01*
X445288Y-324452D01*
X444888D01*
X444488Y-324052D01*
X444088Y-324452D01*
X443688D01*
X444088Y-324852D01*
X443688Y-325252D01*
X444088D01*
X444488Y-325652D01*
Y-325252D02*
X444688Y-325052D01*
X444888D01*
X444688Y-324852D01*
X444888Y-324652D01*
X444688D01*
X444488Y-324452D01*
X444288Y-324652D01*
X444088D01*
X444288Y-324852D01*
X444088Y-325052D01*
X444288D01*
X444488Y-325252D01*
X457480Y-325652D02*
X457880Y-325252D01*
X458280D01*
X457880Y-324852D01*
X458280Y-324452D01*
X457880D01*
X457480Y-324052D01*
X457080Y-324452D01*
X456680D01*
X457080Y-324852D01*
X456680Y-325252D01*
X457080D01*
X457480Y-325652D01*
Y-325252D02*
X457680Y-325052D01*
X457880D01*
X457680Y-324852D01*
X457880Y-324652D01*
X457680D01*
X457480Y-324452D01*
X457280Y-324652D01*
X457080D01*
X457280Y-324852D01*
X457080Y-325052D01*
X457280D01*
X457480Y-325252D01*
X453937Y-325652D02*
X454337Y-325252D01*
X454737D01*
X454337Y-324852D01*
X454737Y-324452D01*
X454337D01*
X453937Y-324052D01*
X453537Y-324452D01*
X453137D01*
X453537Y-324852D01*
X453137Y-325252D01*
X453537D01*
X453937Y-325652D01*
Y-325252D02*
X454137Y-325052D01*
X454337D01*
X454137Y-324852D01*
X454337Y-324652D01*
X454137D01*
X453937Y-324452D01*
X453737Y-324652D01*
X453537D01*
X453737Y-324852D01*
X453537Y-325052D01*
X453737D01*
X453937Y-325252D01*
X440551Y-325652D02*
X440951Y-325252D01*
X441351D01*
X440951Y-324852D01*
X441351Y-324452D01*
X440951D01*
X440551Y-324052D01*
X440151Y-324452D01*
X439751D01*
X440151Y-324852D01*
X439751Y-325252D01*
X440151D01*
X440551Y-325652D01*
Y-325252D02*
X440751Y-325052D01*
X440951D01*
X440751Y-324852D01*
X440951Y-324652D01*
X440751D01*
X440551Y-324452D01*
X440351Y-324652D01*
X440151D01*
X440351Y-324852D01*
X440151Y-325052D01*
X440351D01*
X440551Y-325252D01*
X486221Y-340551D02*
Y-339218D01*
X486887Y-338552D01*
X487553Y-339218D01*
Y-340551D01*
Y-339551D01*
X486221D01*
X222638Y-375455D02*
X223038Y-375055D01*
X223438D01*
X223038Y-374655D01*
X223438Y-374255D01*
X223038D01*
X222638Y-373855D01*
X222238Y-374255D01*
X221838D01*
X222238Y-374655D01*
X221838Y-375055D01*
X222238D01*
X222638Y-375455D01*
Y-375055D02*
X222838Y-374855D01*
X223038D01*
X222838Y-374655D01*
X223038Y-374455D01*
X222838D01*
X222638Y-374255D01*
X222438Y-374455D01*
X222238D01*
X222438Y-374655D01*
X222238Y-374855D01*
X222438D01*
X222638Y-375055D01*
X218445Y-374907D02*
X218845Y-374507D01*
X219245D01*
X218845Y-374108D01*
X219245Y-373708D01*
X218845D01*
X218445Y-373307D01*
X218045Y-373708D01*
X217645D01*
X218045Y-374108D01*
X217645Y-374507D01*
X218045D01*
X218445Y-374907D01*
Y-374507D02*
X218645Y-374307D01*
X218845D01*
X218645Y-374108D01*
X218845Y-373907D01*
X218645D01*
X218445Y-373708D01*
X218245Y-373907D01*
X218045D01*
X218245Y-374108D01*
X218045Y-374307D01*
X218245D01*
X218445Y-374507D01*
X453937Y-307542D02*
X454337Y-307142D01*
X454737D01*
X454337Y-306742D01*
X454737Y-306342D01*
X454337D01*
X453937Y-305942D01*
X453537Y-306342D01*
X453137D01*
X453537Y-306742D01*
X453137Y-307142D01*
X453537D01*
X453937Y-307542D01*
Y-307142D02*
X454137Y-306942D01*
X454337D01*
X454137Y-306742D01*
X454337Y-306542D01*
X454137D01*
X453937Y-306342D01*
X453737Y-306542D01*
X453537D01*
X453737Y-306742D01*
X453537Y-306942D01*
X453737D01*
X453937Y-307142D01*
X451181Y-307542D02*
X451581Y-307142D01*
X451981D01*
X451581Y-306742D01*
X451981Y-306342D01*
X451581D01*
X451181Y-305942D01*
X450781Y-306342D01*
X450381D01*
X450781Y-306742D01*
X450381Y-307142D01*
X450781D01*
X451181Y-307542D01*
Y-307142D02*
X451381Y-306942D01*
X451581D01*
X451381Y-306742D01*
X451581Y-306542D01*
X451381D01*
X451181Y-306342D01*
X450981Y-306542D01*
X450781D01*
X450981Y-306742D01*
X450781Y-306942D01*
X450981D01*
X451181Y-307142D01*
X267286Y-131497D02*
X267686Y-131097D01*
X268086D01*
X267686Y-130697D01*
X268086Y-130297D01*
X267686D01*
X267286Y-129897D01*
X266886Y-130297D01*
X266486D01*
X266886Y-130697D01*
X266486Y-131097D01*
X266886D01*
X267286Y-131497D01*
Y-131097D02*
X267486Y-130897D01*
X267686D01*
X267486Y-130697D01*
X267686Y-130497D01*
X267486D01*
X267286Y-130297D01*
X267086Y-130497D01*
X266886D01*
X267086Y-130697D01*
X266886Y-130897D01*
X267086D01*
X267286Y-131097D01*
X109409Y-140911D02*
X109809Y-140511D01*
X110209D01*
X109809Y-140111D01*
X110209Y-139711D01*
X109809D01*
X109409Y-139311D01*
X109009Y-139711D01*
X108609D01*
X109009Y-140111D01*
X108609Y-140511D01*
X109009D01*
X109409Y-140911D01*
Y-140511D02*
X109609Y-140311D01*
X109809D01*
X109609Y-140111D01*
X109809Y-139911D01*
X109609D01*
X109409Y-139711D01*
X109209Y-139911D01*
X109009D01*
X109209Y-140111D01*
X109009Y-140311D01*
X109209D01*
X109409Y-140511D01*
X105409Y-140911D02*
X105809Y-140511D01*
X106209D01*
X105809Y-140111D01*
X106209Y-139711D01*
X105809D01*
X105409Y-139311D01*
X105009Y-139711D01*
X104609D01*
X105009Y-140111D01*
X104609Y-140511D01*
X105009D01*
X105409Y-140911D01*
Y-140511D02*
X105609Y-140311D01*
X105809D01*
X105609Y-140111D01*
X105809Y-139911D01*
X105609D01*
X105409Y-139711D01*
X105209Y-139911D01*
X105009D01*
X105209Y-140111D01*
X105009Y-140311D01*
X105209D01*
X105409Y-140511D01*
X101409Y-140911D02*
X101810Y-140511D01*
X102209D01*
X101810Y-140111D01*
X102209Y-139711D01*
X101810D01*
X101409Y-139311D01*
X101010Y-139711D01*
X100610D01*
X101010Y-140111D01*
X100610Y-140511D01*
X101010D01*
X101409Y-140911D01*
Y-140511D02*
X101610Y-140311D01*
X101810D01*
X101610Y-140111D01*
X101810Y-139911D01*
X101610D01*
X101409Y-139711D01*
X101209Y-139911D01*
X101010D01*
X101209Y-140111D01*
X101010Y-140311D01*
X101209D01*
X101409Y-140511D01*
X97409Y-140911D02*
X97809Y-140511D01*
X98210D01*
X97809Y-140111D01*
X98210Y-139711D01*
X97809D01*
X97409Y-139311D01*
X97009Y-139711D01*
X96609D01*
X97009Y-140111D01*
X96609Y-140511D01*
X97009D01*
X97409Y-140911D01*
Y-140511D02*
X97610Y-140311D01*
X97809D01*
X97610Y-140111D01*
X97809Y-139911D01*
X97610D01*
X97409Y-139711D01*
X97210Y-139911D01*
X97009D01*
X97210Y-140111D01*
X97009Y-140311D01*
X97210D01*
X97409Y-140511D01*
X399618Y-137628D02*
X400018Y-137228D01*
X400418D01*
X400018Y-136828D01*
X400418Y-136428D01*
X400018D01*
X399618Y-136028D01*
X399218Y-136428D01*
X398818D01*
X399218Y-136828D01*
X398818Y-137228D01*
X399218D01*
X399618Y-137628D01*
Y-137228D02*
X399818Y-137028D01*
X400018D01*
X399818Y-136828D01*
X400018Y-136628D01*
X399818D01*
X399618Y-136428D01*
X399418Y-136628D01*
X399218D01*
X399418Y-136828D01*
X399218Y-137028D01*
X399418D01*
X399618Y-137228D01*
X65945Y-58723D02*
X66345Y-58323D01*
X66745D01*
X66345Y-57923D01*
X66745Y-57523D01*
X66345D01*
X65945Y-57123D01*
X65545Y-57523D01*
X65145D01*
X65545Y-57923D01*
X65145Y-58323D01*
X65545D01*
X65945Y-58723D01*
Y-58323D02*
X66145Y-58123D01*
X66345D01*
X66145Y-57923D01*
X66345Y-57723D01*
X66145D01*
X65945Y-57523D01*
X65745Y-57723D01*
X65545D01*
X65745Y-57923D01*
X65545Y-58123D01*
X65745D01*
X65945Y-58323D01*
X615158Y-9658D02*
X615557Y-9258D01*
X615957D01*
X615557Y-8858D01*
X615957Y-8458D01*
X615557D01*
X615158Y-8058D01*
X614757Y-8458D01*
X614358D01*
X614757Y-8858D01*
X614358Y-9258D01*
X614757D01*
X615158Y-9658D01*
Y-9258D02*
X615357Y-9058D01*
X615557D01*
X615357Y-8858D01*
X615557Y-8658D01*
X615357D01*
X615158Y-8458D01*
X614958Y-8658D01*
X614757D01*
X614958Y-8858D01*
X614757Y-9058D01*
X614958D01*
X615158Y-9258D01*
X70866Y-122847D02*
X71266Y-122447D01*
X71666D01*
X71266Y-122047D01*
X71666Y-121647D01*
X71266D01*
X70866Y-121247D01*
X70466Y-121647D01*
X70066D01*
X70466Y-122047D01*
X70066Y-122447D01*
X70466D01*
X70866Y-122847D01*
Y-122447D02*
X71066Y-122247D01*
X71266D01*
X71066Y-122047D01*
X71266Y-121847D01*
X71066D01*
X70866Y-121647D01*
X70666Y-121847D01*
X70466D01*
X70666Y-122047D01*
X70466Y-122247D01*
X70666D01*
X70866Y-122447D01*
X360204Y-253784D02*
X360604Y-253384D01*
X361004D01*
X360604Y-252984D01*
X361004Y-252584D01*
X360604D01*
X360204Y-252184D01*
X359804Y-252584D01*
X359404D01*
X359804Y-252984D01*
X359404Y-253384D01*
X359804D01*
X360204Y-253784D01*
Y-253384D02*
X360404Y-253184D01*
X360604D01*
X360404Y-252984D01*
X360604Y-252784D01*
X360404D01*
X360204Y-252584D01*
X360004Y-252784D01*
X359804D01*
X360004Y-252984D01*
X359804Y-253184D01*
X360004D01*
X360204Y-253384D01*
X417596Y-175997D02*
X417996Y-175597D01*
X418396D01*
X417996Y-175197D01*
X418396Y-174797D01*
X417996D01*
X417596Y-174397D01*
X417196Y-174797D01*
X416796D01*
X417196Y-175197D01*
X416796Y-175597D01*
X417196D01*
X417596Y-175997D01*
Y-175597D02*
X417796Y-175397D01*
X417996D01*
X417796Y-175197D01*
X417996Y-174997D01*
X417796D01*
X417596Y-174797D01*
X417396Y-174997D01*
X417196D01*
X417396Y-175197D01*
X417196Y-175397D01*
X417396D01*
X417596Y-175597D01*
X377921Y-204540D02*
X378321Y-204140D01*
X378721D01*
X378321Y-203740D01*
X378721Y-203340D01*
X378321D01*
X377921Y-202940D01*
X377521Y-203340D01*
X377121D01*
X377521Y-203740D01*
X377121Y-204140D01*
X377521D01*
X377921Y-204540D01*
Y-204140D02*
X378121Y-203940D01*
X378321D01*
X378121Y-203740D01*
X378321Y-203540D01*
X378121D01*
X377921Y-203340D01*
X377721Y-203540D01*
X377521D01*
X377721Y-203740D01*
X377521Y-203940D01*
X377721D01*
X377921Y-204140D01*
X372016Y-201587D02*
X372416Y-201187D01*
X372816D01*
X372416Y-200787D01*
X372816Y-200387D01*
X372416D01*
X372016Y-199987D01*
X371616Y-200387D01*
X371216D01*
X371616Y-200787D01*
X371216Y-201187D01*
X371616D01*
X372016Y-201587D01*
Y-201187D02*
X372216Y-200987D01*
X372416D01*
X372216Y-200787D01*
X372416Y-200587D01*
X372216D01*
X372016Y-200387D01*
X371816Y-200587D01*
X371616D01*
X371816Y-200787D01*
X371616Y-200987D01*
X371816D01*
X372016Y-201187D01*
X354541Y-224436D02*
X354941Y-224036D01*
X355341D01*
X354941Y-223636D01*
X355341Y-223236D01*
X354941D01*
X354541Y-222836D01*
X354141Y-223236D01*
X353741D01*
X354141Y-223636D01*
X353741Y-224036D01*
X354141D01*
X354541Y-224436D01*
Y-224036D02*
X354741Y-223836D01*
X354941D01*
X354741Y-223636D01*
X354941Y-223436D01*
X354741D01*
X354541Y-223236D01*
X354341Y-223436D01*
X354141D01*
X354341Y-223636D01*
X354141Y-223836D01*
X354341D01*
X354541Y-224036D01*
X354452Y-236036D02*
X354852Y-235636D01*
X355252D01*
X354852Y-235236D01*
X355252Y-234836D01*
X354852D01*
X354452Y-234436D01*
X354052Y-234836D01*
X353652D01*
X354052Y-235236D01*
X353652Y-235636D01*
X354052D01*
X354452Y-236036D01*
Y-235636D02*
X354652Y-235436D01*
X354852D01*
X354652Y-235236D01*
X354852Y-235036D01*
X354652D01*
X354452Y-234836D01*
X354252Y-235036D01*
X354052D01*
X354252Y-235236D01*
X354052Y-235436D01*
X354252D01*
X354452Y-235636D01*
X356578Y-226047D02*
X356978Y-225647D01*
X357378D01*
X356978Y-225247D01*
X357378Y-224847D01*
X356978D01*
X356578Y-224447D01*
X356178Y-224847D01*
X355778D01*
X356178Y-225247D01*
X355778Y-225647D01*
X356178D01*
X356578Y-226047D01*
Y-225647D02*
X356778Y-225447D01*
X356978D01*
X356778Y-225247D01*
X356978Y-225047D01*
X356778D01*
X356578Y-224847D01*
X356378Y-225047D01*
X356178D01*
X356378Y-225247D01*
X356178Y-225447D01*
X356378D01*
X356578Y-225647D01*
X379921Y-202540D02*
X380321Y-202140D01*
X380721D01*
X380321Y-201740D01*
X380721Y-201340D01*
X380321D01*
X379921Y-200940D01*
X379521Y-201340D01*
X379121D01*
X379521Y-201740D01*
X379121Y-202140D01*
X379521D01*
X379921Y-202540D01*
Y-202140D02*
X380121Y-201940D01*
X380321D01*
X380121Y-201740D01*
X380321Y-201540D01*
X380121D01*
X379921Y-201340D01*
X379721Y-201540D01*
X379521D01*
X379721Y-201740D01*
X379521Y-201940D01*
X379721D01*
X379921Y-202140D01*
X102528Y-212383D02*
X102928Y-211983D01*
X103328D01*
X102928Y-211583D01*
X103328Y-211183D01*
X102928D01*
X102528Y-210783D01*
X102128Y-211183D01*
X101728D01*
X102128Y-211583D01*
X101728Y-211983D01*
X102128D01*
X102528Y-212383D01*
Y-211983D02*
X102728Y-211783D01*
X102928D01*
X102728Y-211583D01*
X102928Y-211383D01*
X102728D01*
X102528Y-211183D01*
X102328Y-211383D01*
X102128D01*
X102328Y-211583D01*
X102128Y-211783D01*
X102328D01*
X102528Y-211983D01*
X97125Y-220288D02*
X97525Y-219888D01*
X97925D01*
X97525Y-219488D01*
X97925Y-219088D01*
X97525D01*
X97125Y-218688D01*
X96725Y-219088D01*
X96325D01*
X96725Y-219488D01*
X96325Y-219888D01*
X96725D01*
X97125Y-220288D01*
Y-219888D02*
X97325Y-219688D01*
X97525D01*
X97325Y-219488D01*
X97525Y-219288D01*
X97325D01*
X97125Y-219088D01*
X96925Y-219288D01*
X96725D01*
X96925Y-219488D01*
X96725Y-219688D01*
X96925D01*
X97125Y-219888D01*
X99410Y-217335D02*
X99809Y-216935D01*
X100209D01*
X99809Y-216535D01*
X100209Y-216135D01*
X99809D01*
X99410Y-215735D01*
X99010Y-216135D01*
X98610D01*
X99010Y-216535D01*
X98610Y-216935D01*
X99010D01*
X99410Y-217335D01*
Y-216935D02*
X99610Y-216735D01*
X99809D01*
X99610Y-216535D01*
X99809Y-216335D01*
X99610D01*
X99410Y-216135D01*
X99209Y-216335D01*
X99010D01*
X99209Y-216535D01*
X99010Y-216735D01*
X99209D01*
X99410Y-216935D01*
X101378Y-215367D02*
X101778Y-214967D01*
X102178D01*
X101778Y-214567D01*
X102178Y-214167D01*
X101778D01*
X101378Y-213767D01*
X100978Y-214167D01*
X100578D01*
X100978Y-214567D01*
X100578Y-214967D01*
X100978D01*
X101378Y-215367D01*
Y-214967D02*
X101578Y-214767D01*
X101778D01*
X101578Y-214567D01*
X101778Y-214367D01*
X101578D01*
X101378Y-214167D01*
X101178Y-214367D01*
X100978D01*
X101178Y-214567D01*
X100978Y-214767D01*
X101178D01*
X101378Y-214967D01*
X86614Y-175997D02*
X87014Y-175597D01*
X87414D01*
X87014Y-175197D01*
X87414Y-174797D01*
X87014D01*
X86614Y-174397D01*
X86214Y-174797D01*
X85814D01*
X86214Y-175197D01*
X85814Y-175597D01*
X86214D01*
X86614Y-175997D01*
Y-175597D02*
X86814Y-175397D01*
X87014D01*
X86814Y-175197D01*
X87014Y-174997D01*
X86814D01*
X86614Y-174797D01*
X86414Y-174997D01*
X86214D01*
X86414Y-175197D01*
X86214Y-175397D01*
X86414D01*
X86614Y-175597D01*
X361652Y-236005D02*
X362052Y-235605D01*
X362452D01*
X362052Y-235205D01*
X362452Y-234805D01*
X362052D01*
X361652Y-234405D01*
X361252Y-234805D01*
X360852D01*
X361252Y-235205D01*
X360852Y-235605D01*
X361252D01*
X361652Y-236005D01*
Y-235605D02*
X361852Y-235405D01*
X362052D01*
X361852Y-235205D01*
X362052Y-235005D01*
X361852D01*
X361652Y-234805D01*
X361452Y-235005D01*
X361252D01*
X361452Y-235205D01*
X361252Y-235405D01*
X361452D01*
X361652Y-235605D01*
X359131Y-224225D02*
X359531Y-223825D01*
X359931D01*
X359531Y-223425D01*
X359931Y-223025D01*
X359531D01*
X359131Y-222625D01*
X358731Y-223025D01*
X358331D01*
X358731Y-223425D01*
X358331Y-223825D01*
X358731D01*
X359131Y-224225D01*
Y-223825D02*
X359331Y-223625D01*
X359531D01*
X359331Y-223425D01*
X359531Y-223225D01*
X359331D01*
X359131Y-223025D01*
X358931Y-223225D01*
X358731D01*
X358931Y-223425D01*
X358731Y-223625D01*
X358931D01*
X359131Y-223825D01*
X361531Y-224225D02*
X361931Y-223825D01*
X362331D01*
X361931Y-223425D01*
X362331Y-223025D01*
X361931D01*
X361531Y-222625D01*
X361131Y-223025D01*
X360731D01*
X361131Y-223425D01*
X360731Y-223825D01*
X361131D01*
X361531Y-224225D01*
Y-223825D02*
X361731Y-223625D01*
X361931D01*
X361731Y-223425D01*
X361931Y-223225D01*
X361731D01*
X361531Y-223025D01*
X361331Y-223225D01*
X361131D01*
X361331Y-223425D01*
X361131Y-223625D01*
X361331D01*
X361531Y-223825D01*
X360236Y-262986D02*
X360636Y-262586D01*
X361036D01*
X360636Y-262186D01*
X361036Y-261786D01*
X360636D01*
X360236Y-261386D01*
X359836Y-261786D01*
X359436D01*
X359836Y-262186D01*
X359436Y-262586D01*
X359836D01*
X360236Y-262986D01*
Y-262586D02*
X360436Y-262386D01*
X360636D01*
X360436Y-262186D01*
X360636Y-261986D01*
X360436D01*
X360236Y-261786D01*
X360036Y-261986D01*
X359836D01*
X360036Y-262186D01*
X359836Y-262386D01*
X360036D01*
X360236Y-262586D01*
Y-266986D02*
X360636Y-266586D01*
X361036D01*
X360636Y-266186D01*
X361036Y-265786D01*
X360636D01*
X360236Y-265386D01*
X359836Y-265786D01*
X359436D01*
X359836Y-266186D01*
X359436Y-266586D01*
X359836D01*
X360236Y-266986D01*
Y-266586D02*
X360436Y-266386D01*
X360636D01*
X360436Y-266186D01*
X360636Y-265986D01*
X360436D01*
X360236Y-265786D01*
X360036Y-265986D01*
X359836D01*
X360036Y-266186D01*
X359836Y-266386D01*
X360036D01*
X360236Y-266586D01*
X85416Y-318499D02*
X85816Y-318099D01*
X86216D01*
X85816Y-317699D01*
X86216Y-317299D01*
X85816D01*
X85416Y-316899D01*
X85016Y-317299D01*
X84616D01*
X85016Y-317699D01*
X84616Y-318099D01*
X85016D01*
X85416Y-318499D01*
Y-318099D02*
X85616Y-317899D01*
X85816D01*
X85616Y-317699D01*
X85816Y-317499D01*
X85616D01*
X85416Y-317299D01*
X85216Y-317499D01*
X85016D01*
X85216Y-317699D01*
X85016Y-317899D01*
X85216D01*
X85416Y-318099D01*
X85630Y-264580D02*
X86030Y-264179D01*
X86430D01*
X86030Y-263779D01*
X86430Y-263380D01*
X86030D01*
X85630Y-262980D01*
X85230Y-263380D01*
X84830D01*
X85230Y-263779D01*
X84830Y-264179D01*
X85230D01*
X85630Y-264580D01*
Y-264179D02*
X85830Y-263980D01*
X86030D01*
X85830Y-263779D01*
X86030Y-263580D01*
X85830D01*
X85630Y-263380D01*
X85430Y-263580D01*
X85230D01*
X85430Y-263779D01*
X85230Y-263980D01*
X85430D01*
X85630Y-264179D01*
X86562Y-211983D02*
X86962Y-211583D01*
X87362D01*
X86962Y-211183D01*
X87362Y-210783D01*
X86962D01*
X86562Y-210383D01*
X86162Y-210783D01*
X85762D01*
X86162Y-211183D01*
X85762Y-211583D01*
X86162D01*
X86562Y-211983D01*
Y-211583D02*
X86762Y-211383D01*
X86962D01*
X86762Y-211183D01*
X86962Y-210983D01*
X86762D01*
X86562Y-210783D01*
X86362Y-210983D01*
X86162D01*
X86362Y-211183D01*
X86162Y-211383D01*
X86362D01*
X86562Y-211583D01*
X411043Y-175774D02*
X411443Y-175374D01*
X411843D01*
X411443Y-174974D01*
X411843Y-174574D01*
X411443D01*
X411043Y-174174D01*
X410643Y-174574D01*
X410243D01*
X410643Y-174974D01*
X410243Y-175374D01*
X410643D01*
X411043Y-175774D01*
Y-175374D02*
X411243Y-175174D01*
X411443D01*
X411243Y-174974D01*
X411443Y-174774D01*
X411243D01*
X411043Y-174574D01*
X410843Y-174774D01*
X410643D01*
X410843Y-174974D01*
X410643Y-175174D01*
X410843D01*
X411043Y-175374D01*
X413440Y-175650D02*
X413839Y-175250D01*
X414240D01*
X413839Y-174850D01*
X414240Y-174450D01*
X413839D01*
X413440Y-174050D01*
X413039Y-174450D01*
X412640D01*
X413039Y-174850D01*
X412640Y-175250D01*
X413039D01*
X413440Y-175650D01*
Y-175250D02*
X413639Y-175050D01*
X413839D01*
X413639Y-174850D01*
X413839Y-174650D01*
X413639D01*
X413440Y-174450D01*
X413239Y-174650D01*
X413039D01*
X413239Y-174850D01*
X413039Y-175050D01*
X413239D01*
X413440Y-175250D01*
X421596Y-175834D02*
X421996Y-175434D01*
X422396D01*
X421996Y-175034D01*
X422396Y-174634D01*
X421996D01*
X421596Y-174234D01*
X421196Y-174634D01*
X420796D01*
X421196Y-175034D01*
X420796Y-175434D01*
X421196D01*
X421596Y-175834D01*
Y-175434D02*
X421796Y-175234D01*
X421996D01*
X421796Y-175034D01*
X421996Y-174834D01*
X421796D01*
X421596Y-174634D01*
X421396Y-174834D01*
X421196D01*
X421396Y-175034D01*
X421196Y-175234D01*
X421396D01*
X421596Y-175434D01*
X406528Y-158567D02*
X406928Y-158167D01*
X407328D01*
X406928Y-157767D01*
X407328Y-157367D01*
X406928D01*
X406528Y-156967D01*
X406128Y-157367D01*
X405728D01*
X406128Y-157767D01*
X405728Y-158167D01*
X406128D01*
X406528Y-158567D01*
Y-158167D02*
X406728Y-157967D01*
X406928D01*
X406728Y-157767D01*
X406928Y-157567D01*
X406728D01*
X406528Y-157367D01*
X406328Y-157567D01*
X406128D01*
X406328Y-157767D01*
X406128Y-157967D01*
X406328D01*
X406528Y-158167D01*
X404528Y-164186D02*
X404928Y-163786D01*
X405328D01*
X404928Y-163386D01*
X405328Y-162986D01*
X404928D01*
X404528Y-162586D01*
X404128Y-162986D01*
X403728D01*
X404128Y-163386D01*
X403728Y-163786D01*
X404128D01*
X404528Y-164186D01*
Y-163786D02*
X404728Y-163586D01*
X404928D01*
X404728Y-163386D01*
X404928Y-163186D01*
X404728D01*
X404528Y-162986D01*
X404328Y-163186D01*
X404128D01*
X404328Y-163386D01*
X404128Y-163586D01*
X404328D01*
X404528Y-163786D01*
X407480Y-161233D02*
X407880Y-160833D01*
X408280D01*
X407880Y-160433D01*
X408280Y-160033D01*
X407880D01*
X407480Y-159633D01*
X407080Y-160033D01*
X406680D01*
X407080Y-160433D01*
X406680Y-160833D01*
X407080D01*
X407480Y-161233D01*
Y-160833D02*
X407680Y-160633D01*
X407880D01*
X407680Y-160433D01*
X407880Y-160233D01*
X407680D01*
X407480Y-160033D01*
X407280Y-160233D01*
X407080D01*
X407280Y-160433D01*
X407080Y-160633D01*
X407280D01*
X407480Y-160833D01*
X86614Y-222257D02*
X87014Y-221857D01*
X87414D01*
X87014Y-221457D01*
X87414Y-221057D01*
X87014D01*
X86614Y-220657D01*
X86214Y-221057D01*
X85814D01*
X86214Y-221457D01*
X85814Y-221857D01*
X86214D01*
X86614Y-222257D01*
Y-221857D02*
X86814Y-221657D01*
X87014D01*
X86814Y-221457D01*
X87014Y-221257D01*
X86814D01*
X86614Y-221057D01*
X86414Y-221257D01*
X86214D01*
X86414Y-221457D01*
X86214Y-221657D01*
X86414D01*
X86614Y-221857D01*
X427165Y-176046D02*
X427565Y-175646D01*
X427965D01*
X427565Y-175246D01*
X427965Y-174846D01*
X427565D01*
X427165Y-174446D01*
X426765Y-174846D01*
X426365D01*
X426765Y-175246D01*
X426365Y-175646D01*
X426765D01*
X427165Y-176046D01*
Y-175646D02*
X427365Y-175446D01*
X427565D01*
X427365Y-175246D01*
X427565Y-175046D01*
X427365D01*
X427165Y-174846D01*
X426965Y-175046D01*
X426765D01*
X426965Y-175246D01*
X426765Y-175446D01*
X426965D01*
X427165Y-175646D01*
X75787Y-233084D02*
X76187Y-232683D01*
X76587D01*
X76187Y-232283D01*
X76587Y-231884D01*
X76187D01*
X75787Y-231484D01*
X75387Y-231884D01*
X74987D01*
X75387Y-232283D01*
X74987Y-232683D01*
X75387D01*
X75787Y-233084D01*
Y-232683D02*
X75987Y-232484D01*
X76187D01*
X75987Y-232283D01*
X76187Y-232084D01*
X75987D01*
X75787Y-231884D01*
X75587Y-232084D01*
X75387D01*
X75587Y-232283D01*
X75387Y-232484D01*
X75587D01*
X75787Y-232683D01*
X87167Y-167177D02*
X87567Y-166777D01*
X87967D01*
X87567Y-166377D01*
X87967Y-165977D01*
X87567D01*
X87167Y-165577D01*
X86767Y-165977D01*
X86367D01*
X86767Y-166377D01*
X86367Y-166777D01*
X86767D01*
X87167Y-167177D01*
Y-166777D02*
X87367Y-166577D01*
X87567D01*
X87367Y-166377D01*
X87567Y-166177D01*
X87367D01*
X87167Y-165977D01*
X86967Y-166177D01*
X86767D01*
X86967Y-166377D01*
X86767Y-166577D01*
X86967D01*
X87167Y-166777D01*
X89567Y-167170D02*
X89967Y-166770D01*
X90367D01*
X89967Y-166370D01*
X90367Y-165970D01*
X89967D01*
X89567Y-165570D01*
X89167Y-165970D01*
X88767D01*
X89167Y-166370D01*
X88767Y-166770D01*
X89167D01*
X89567Y-167170D01*
Y-166770D02*
X89767Y-166570D01*
X89967D01*
X89767Y-166370D01*
X89967Y-166170D01*
X89767D01*
X89567Y-165970D01*
X89367Y-166170D01*
X89167D01*
X89367Y-166370D01*
X89167Y-166570D01*
X89367D01*
X89567Y-166770D01*
X85630Y-214383D02*
X86030Y-213983D01*
X86430D01*
X86030Y-213583D01*
X86430Y-213183D01*
X86030D01*
X85630Y-212783D01*
X85230Y-213183D01*
X84830D01*
X85230Y-213583D01*
X84830Y-213983D01*
X85230D01*
X85630Y-214383D01*
Y-213983D02*
X85830Y-213783D01*
X86030D01*
X85830Y-213583D01*
X86030Y-213383D01*
X85830D01*
X85630Y-213183D01*
X85430Y-213383D01*
X85230D01*
X85430Y-213583D01*
X85230Y-213783D01*
X85430D01*
X85630Y-213983D01*
Y-266980D02*
X86030Y-266580D01*
X86430D01*
X86030Y-266179D01*
X86430Y-265779D01*
X86030D01*
X85630Y-265380D01*
X85230Y-265779D01*
X84830D01*
X85230Y-266179D01*
X84830Y-266580D01*
X85230D01*
X85630Y-266980D01*
Y-266580D02*
X85830Y-266379D01*
X86030D01*
X85830Y-266179D01*
X86030Y-265980D01*
X85830D01*
X85630Y-265779D01*
X85430Y-265980D01*
X85230D01*
X85430Y-266179D01*
X85230Y-266379D01*
X85430D01*
X85630Y-266580D01*
Y-321113D02*
X86030Y-320713D01*
X86430D01*
X86030Y-320313D01*
X86430Y-319913D01*
X86030D01*
X85630Y-319513D01*
X85230Y-319913D01*
X84830D01*
X85230Y-320313D01*
X84830Y-320713D01*
X85230D01*
X85630Y-321113D01*
Y-320713D02*
X85830Y-320513D01*
X86030D01*
X85830Y-320313D01*
X86030Y-320113D01*
X85830D01*
X85630Y-319913D01*
X85430Y-320113D01*
X85230D01*
X85430Y-320313D01*
X85230Y-320513D01*
X85430D01*
X85630Y-320713D01*
X543276Y-227391D02*
X543676Y-226991D01*
X544076D01*
X543676Y-226591D01*
X544076Y-226191D01*
X543676D01*
X543276Y-225791D01*
X542876Y-226191D01*
X542476D01*
X542876Y-226591D01*
X542476Y-226991D01*
X542876D01*
X543276Y-227391D01*
Y-226991D02*
X543476Y-226791D01*
X543676D01*
X543476Y-226591D01*
X543676Y-226391D01*
X543476D01*
X543276Y-226191D01*
X543076Y-226391D01*
X542876D01*
X543076Y-226591D01*
X542876Y-226791D01*
X543076D01*
X543276Y-226991D01*
X544294Y-225048D02*
X544694Y-224648D01*
X545094D01*
X544694Y-224248D01*
X545094Y-223848D01*
X544694D01*
X544294Y-223448D01*
X543894Y-223848D01*
X543494D01*
X543894Y-224248D01*
X543494Y-224648D01*
X543894D01*
X544294Y-225048D01*
Y-224648D02*
X544494Y-224448D01*
X544694D01*
X544494Y-224248D01*
X544694Y-224048D01*
X544494D01*
X544294Y-223848D01*
X544094Y-224048D01*
X543894D01*
X544094Y-224248D01*
X543894Y-224448D01*
X544094D01*
X544294Y-224648D01*
X544291Y-234068D02*
X544691Y-233668D01*
X545091D01*
X544691Y-233268D01*
X545091Y-232868D01*
X544691D01*
X544291Y-232468D01*
X543891Y-232868D01*
X543491D01*
X543891Y-233268D01*
X543491Y-233668D01*
X543891D01*
X544291Y-234068D01*
Y-233668D02*
X544491Y-233468D01*
X544691D01*
X544491Y-233268D01*
X544691Y-233068D01*
X544491D01*
X544291Y-232868D01*
X544091Y-233068D01*
X543891D01*
X544091Y-233268D01*
X543891Y-233468D01*
X544091D01*
X544291Y-233668D01*
X359252Y-236036D02*
X359652Y-235636D01*
X360052D01*
X359652Y-235236D01*
X360052Y-234836D01*
X359652D01*
X359252Y-234436D01*
X358852Y-234836D01*
X358452D01*
X358852Y-235236D01*
X358452Y-235636D01*
X358852D01*
X359252Y-236036D01*
Y-235636D02*
X359452Y-235436D01*
X359652D01*
X359452Y-235236D01*
X359652Y-235036D01*
X359452D01*
X359252Y-234836D01*
X359052Y-235036D01*
X358852D01*
X359052Y-235236D01*
X358852Y-235436D01*
X359052D01*
X359252Y-235636D01*
X356852Y-236036D02*
X357252Y-235636D01*
X357652D01*
X357252Y-235236D01*
X357652Y-234836D01*
X357252D01*
X356852Y-234436D01*
X356452Y-234836D01*
X356052D01*
X356452Y-235236D01*
X356052Y-235636D01*
X356452D01*
X356852Y-236036D01*
Y-235636D02*
X357052Y-235436D01*
X357252D01*
X357052Y-235236D01*
X357252Y-235036D01*
X357052D01*
X356852Y-234836D01*
X356652Y-235036D01*
X356452D01*
X356652Y-235236D01*
X356452Y-235436D01*
X356652D01*
X356852Y-235636D01*
X407480Y-164186D02*
X407880Y-163786D01*
X408280D01*
X407880Y-163386D01*
X408280Y-162986D01*
X407880D01*
X407480Y-162586D01*
X407080Y-162986D01*
X406680D01*
X407080Y-163386D01*
X406680Y-163786D01*
X407080D01*
X407480Y-164186D01*
Y-163786D02*
X407680Y-163586D01*
X407880D01*
X407680Y-163386D01*
X407880Y-163186D01*
X407680D01*
X407480Y-162986D01*
X407280Y-163186D01*
X407080D01*
X407280Y-163386D01*
X407080Y-163586D01*
X407280D01*
X407480Y-163786D01*
X47244Y-9658D02*
X47644Y-9258D01*
X48044D01*
X47644Y-8858D01*
X48044Y-8458D01*
X47644D01*
X47244Y-8058D01*
X46844Y-8458D01*
X46444D01*
X46844Y-8858D01*
X46444Y-9258D01*
X46844D01*
X47244Y-9658D01*
Y-9258D02*
X47444Y-9058D01*
X47644D01*
X47444Y-8858D01*
X47644Y-8658D01*
X47444D01*
X47244Y-8458D01*
X47044Y-8658D01*
X46844D01*
X47044Y-8858D01*
X46844Y-9058D01*
X47044D01*
X47244Y-9258D01*
X40354Y-9658D02*
X40754Y-9258D01*
X41154D01*
X40754Y-8858D01*
X41154Y-8458D01*
X40754D01*
X40354Y-8058D01*
X39954Y-8458D01*
X39554D01*
X39954Y-8858D01*
X39554Y-9258D01*
X39954D01*
X40354Y-9658D01*
Y-9258D02*
X40554Y-9058D01*
X40754D01*
X40554Y-8858D01*
X40754Y-8658D01*
X40554D01*
X40354Y-8458D01*
X40154Y-8658D01*
X39954D01*
X40154Y-8858D01*
X39954Y-9058D01*
X40154D01*
X40354Y-9258D01*
X33465Y-9658D02*
X33865Y-9258D01*
X34265D01*
X33865Y-8858D01*
X34265Y-8458D01*
X33865D01*
X33465Y-8058D01*
X33065Y-8458D01*
X32665D01*
X33065Y-8858D01*
X32665Y-9258D01*
X33065D01*
X33465Y-9658D01*
Y-9258D02*
X33665Y-9058D01*
X33865D01*
X33665Y-8858D01*
X33865Y-8658D01*
X33665D01*
X33465Y-8458D01*
X33265Y-8658D01*
X33065D01*
X33265Y-8858D01*
X33065Y-9058D01*
X33265D01*
X33465Y-9258D01*
X26575Y18885D02*
X26975Y19285D01*
X27375D01*
X26975Y19685D01*
X27375Y20085D01*
X26975D01*
X26575Y20485D01*
X26175Y20085D01*
X25775D01*
X26175Y19685D01*
X25775Y19285D01*
X26175D01*
X26575Y18885D01*
Y19285D02*
X26775Y19485D01*
X26975D01*
X26775Y19685D01*
X26975Y19885D01*
X26775D01*
X26575Y20085D01*
X26375Y19885D01*
X26175D01*
X26375Y19685D01*
X26175Y19485D01*
X26375D01*
X26575Y19285D01*
X86614Y-228162D02*
X87014Y-227762D01*
X87414D01*
X87014Y-227362D01*
X87414Y-226962D01*
X87014D01*
X86614Y-226562D01*
X86214Y-226962D01*
X85814D01*
X86214Y-227362D01*
X85814Y-227762D01*
X86214D01*
X86614Y-228162D01*
Y-227762D02*
X86814Y-227562D01*
X87014D01*
X86814Y-227362D01*
X87014Y-227162D01*
X86814D01*
X86614Y-226962D01*
X86414Y-227162D01*
X86214D01*
X86414Y-227362D01*
X86214Y-227562D01*
X86414D01*
X86614Y-227762D01*
X63976Y-222257D02*
X64376Y-221857D01*
X64776D01*
X64376Y-221457D01*
X64776Y-221057D01*
X64376D01*
X63976Y-220657D01*
X63576Y-221057D01*
X63176D01*
X63576Y-221457D01*
X63176Y-221857D01*
X63576D01*
X63976Y-222257D01*
Y-221857D02*
X64176Y-221657D01*
X64376D01*
X64176Y-221457D01*
X64376Y-221257D01*
X64176D01*
X63976Y-221057D01*
X63776Y-221257D01*
X63576D01*
X63776Y-221457D01*
X63576Y-221657D01*
X63776D01*
X63976Y-221857D01*
X82677Y-233084D02*
X83077Y-232683D01*
X83477D01*
X83077Y-232283D01*
X83477Y-231884D01*
X83077D01*
X82677Y-231484D01*
X82277Y-231884D01*
X81877D01*
X82277Y-232283D01*
X81877Y-232683D01*
X82277D01*
X82677Y-233084D01*
Y-232683D02*
X82877Y-232484D01*
X83077D01*
X82877Y-232283D01*
X83077Y-232084D01*
X82877D01*
X82677Y-231884D01*
X82477Y-232084D01*
X82277D01*
X82477Y-232283D01*
X82277Y-232484D01*
X82477D01*
X82677Y-232683D01*
X63976Y-276391D02*
X64376Y-275991D01*
X64776D01*
X64376Y-275590D01*
X64776Y-275190D01*
X64376D01*
X63976Y-274791D01*
X63576Y-275190D01*
X63176D01*
X63576Y-275590D01*
X63176Y-275991D01*
X63576D01*
X63976Y-276391D01*
Y-275991D02*
X64176Y-275791D01*
X64376D01*
X64176Y-275590D01*
X64376Y-275391D01*
X64176D01*
X63976Y-275190D01*
X63776Y-275391D01*
X63576D01*
X63776Y-275590D01*
X63576Y-275791D01*
X63776D01*
X63976Y-275991D01*
X75787Y-286233D02*
X76187Y-285833D01*
X76587D01*
X76187Y-285433D01*
X76587Y-285033D01*
X76187D01*
X75787Y-284633D01*
X75387Y-285033D01*
X74987D01*
X75387Y-285433D01*
X74987Y-285833D01*
X75387D01*
X75787Y-286233D01*
Y-285833D02*
X75987Y-285633D01*
X76187D01*
X75987Y-285433D01*
X76187Y-285233D01*
X75987D01*
X75787Y-285033D01*
X75587Y-285233D01*
X75387D01*
X75587Y-285433D01*
X75387Y-285633D01*
X75587D01*
X75787Y-285833D01*
X87598Y-276391D02*
X87998Y-275991D01*
X88398D01*
X87998Y-275590D01*
X88398Y-275190D01*
X87998D01*
X87598Y-274791D01*
X87198Y-275190D01*
X86798D01*
X87198Y-275590D01*
X86798Y-275991D01*
X87198D01*
X87598Y-276391D01*
Y-275991D02*
X87798Y-275791D01*
X87998D01*
X87798Y-275590D01*
X87998Y-275391D01*
X87798D01*
X87598Y-275190D01*
X87398Y-275391D01*
X87198D01*
X87398Y-275590D01*
X87198Y-275791D01*
X87398D01*
X87598Y-275991D01*
Y-282296D02*
X87998Y-281896D01*
X88398D01*
X87998Y-281496D01*
X88398Y-281096D01*
X87998D01*
X87598Y-280696D01*
X87198Y-281096D01*
X86798D01*
X87198Y-281496D01*
X86798Y-281896D01*
X87198D01*
X87598Y-282296D01*
Y-281896D02*
X87798Y-281696D01*
X87998D01*
X87798Y-281496D01*
X87998Y-281296D01*
X87798D01*
X87598Y-281096D01*
X87398Y-281296D01*
X87198D01*
X87398Y-281496D01*
X87198Y-281696D01*
X87398D01*
X87598Y-281896D01*
X81880Y-288382D02*
X82280Y-287982D01*
X82680D01*
X82280Y-287582D01*
X82680Y-287182D01*
X82280D01*
X81880Y-286782D01*
X81480Y-287182D01*
X81080D01*
X81480Y-287582D01*
X81080Y-287982D01*
X81480D01*
X81880Y-288382D01*
Y-287982D02*
X82080Y-287782D01*
X82280D01*
X82080Y-287582D01*
X82280Y-287382D01*
X82080D01*
X81880Y-287182D01*
X81680Y-287382D01*
X81480D01*
X81680Y-287582D01*
X81480Y-287782D01*
X81680D01*
X81880Y-287982D01*
X62992Y-330524D02*
X63392Y-330124D01*
X63792D01*
X63392Y-329724D01*
X63792Y-329324D01*
X63392D01*
X62992Y-328924D01*
X62592Y-329324D01*
X62192D01*
X62592Y-329724D01*
X62192Y-330124D01*
X62592D01*
X62992Y-330524D01*
Y-330124D02*
X63192Y-329924D01*
X63392D01*
X63192Y-329724D01*
X63392Y-329524D01*
X63192D01*
X62992Y-329324D01*
X62792Y-329524D01*
X62592D01*
X62792Y-329724D01*
X62592Y-329924D01*
X62792D01*
X62992Y-330124D01*
X74803Y-340367D02*
X75203Y-339967D01*
X75603D01*
X75203Y-339567D01*
X75603Y-339167D01*
X75203D01*
X74803Y-338767D01*
X74403Y-339167D01*
X74003D01*
X74403Y-339567D01*
X74003Y-339967D01*
X74403D01*
X74803Y-340367D01*
Y-339967D02*
X75003Y-339767D01*
X75203D01*
X75003Y-339567D01*
X75203Y-339367D01*
X75003D01*
X74803Y-339167D01*
X74603Y-339367D01*
X74403D01*
X74603Y-339567D01*
X74403Y-339767D01*
X74603D01*
X74803Y-339967D01*
X78740Y-341351D02*
X79140Y-340951D01*
X79540D01*
X79140Y-340551D01*
X79540Y-340151D01*
X79140D01*
X78740Y-339751D01*
X78340Y-340151D01*
X77940D01*
X78340Y-340551D01*
X77940Y-340951D01*
X78340D01*
X78740Y-341351D01*
Y-340951D02*
X78940Y-340751D01*
X79140D01*
X78940Y-340551D01*
X79140Y-340351D01*
X78940D01*
X78740Y-340151D01*
X78540Y-340351D01*
X78340D01*
X78540Y-340551D01*
X78340Y-340751D01*
X78540D01*
X78740Y-340951D01*
X87598Y-336430D02*
X87998Y-336030D01*
X88398D01*
X87998Y-335630D01*
X88398Y-335230D01*
X87998D01*
X87598Y-334830D01*
X87198Y-335230D01*
X86798D01*
X87198Y-335630D01*
X86798Y-336030D01*
X87198D01*
X87598Y-336430D01*
Y-336030D02*
X87798Y-335830D01*
X87998D01*
X87798Y-335630D01*
X87998Y-335430D01*
X87798D01*
X87598Y-335230D01*
X87398Y-335430D01*
X87198D01*
X87398Y-335630D01*
X87198Y-335830D01*
X87398D01*
X87598Y-336030D01*
Y-330524D02*
X87998Y-330124D01*
X88398D01*
X87998Y-329724D01*
X88398Y-329324D01*
X87998D01*
X87598Y-328924D01*
X87198Y-329324D01*
X86798D01*
X87198Y-329724D01*
X86798Y-330124D01*
X87198D01*
X87598Y-330524D01*
Y-330124D02*
X87798Y-329924D01*
X87998D01*
X87798Y-329724D01*
X87998Y-329524D01*
X87798D01*
X87598Y-329324D01*
X87398Y-329524D01*
X87198D01*
X87398Y-329724D01*
X87198Y-329924D01*
X87398D01*
X87598Y-330124D01*
X63976Y-179934D02*
X64376Y-179534D01*
X64776D01*
X64376Y-179134D01*
X64776Y-178734D01*
X64376D01*
X63976Y-178334D01*
X63576Y-178734D01*
X63176D01*
X63576Y-179134D01*
X63176Y-179534D01*
X63576D01*
X63976Y-179934D01*
Y-179534D02*
X64176Y-179334D01*
X64376D01*
X64176Y-179134D01*
X64376Y-178934D01*
X64176D01*
X63976Y-178734D01*
X63776Y-178934D01*
X63576D01*
X63776Y-179134D01*
X63576Y-179334D01*
X63776D01*
X63976Y-179534D01*
X74803Y-179934D02*
X75203Y-179534D01*
X75603D01*
X75203Y-179134D01*
X75603Y-178734D01*
X75203D01*
X74803Y-178334D01*
X74403Y-178734D01*
X74003D01*
X74403Y-179134D01*
X74003Y-179534D01*
X74403D01*
X74803Y-179934D01*
Y-179534D02*
X75003Y-179334D01*
X75203D01*
X75003Y-179134D01*
X75203Y-178934D01*
X75003D01*
X74803Y-178734D01*
X74603Y-178934D01*
X74403D01*
X74603Y-179134D01*
X74403Y-179334D01*
X74603D01*
X74803Y-179534D01*
X86562Y-170057D02*
X86962Y-169657D01*
X87362D01*
X86962Y-169257D01*
X87362Y-168857D01*
X86962D01*
X86562Y-168457D01*
X86162Y-168857D01*
X85762D01*
X86162Y-169257D01*
X85762Y-169657D01*
X86162D01*
X86562Y-170057D01*
Y-169657D02*
X86762Y-169457D01*
X86962D01*
X86762Y-169257D01*
X86962Y-169057D01*
X86762D01*
X86562Y-168857D01*
X86362Y-169057D01*
X86162D01*
X86362Y-169257D01*
X86162Y-169457D01*
X86362D01*
X86562Y-169657D01*
X80709Y-180918D02*
X81109Y-180518D01*
X81509D01*
X81109Y-180118D01*
X81509Y-179718D01*
X81109D01*
X80709Y-179318D01*
X80309Y-179718D01*
X79909D01*
X80309Y-180118D01*
X79909Y-180518D01*
X80309D01*
X80709Y-180918D01*
Y-180518D02*
X80909Y-180318D01*
X81109D01*
X80909Y-180118D01*
X81109Y-179918D01*
X80909D01*
X80709Y-179718D01*
X80509Y-179918D01*
X80309D01*
X80509Y-180118D01*
X80309Y-180318D01*
X80509D01*
X80709Y-180518D01*
X26575Y-284265D02*
X26975Y-283865D01*
X27375D01*
X26975Y-283465D01*
X27375Y-283065D01*
X26975D01*
X26575Y-282665D01*
X26175Y-283065D01*
X25775D01*
X26175Y-283465D01*
X25775Y-283865D01*
X26175D01*
X26575Y-284265D01*
Y-283865D02*
X26775Y-283665D01*
X26975D01*
X26775Y-283465D01*
X26975Y-283265D01*
X26775D01*
X26575Y-283065D01*
X26375Y-283265D01*
X26175D01*
X26375Y-283465D01*
X26175Y-283665D01*
X26375D01*
X26575Y-283865D01*
X30512Y-171076D02*
X30912Y-170676D01*
X31312D01*
X30912Y-170276D01*
X31312Y-169876D01*
X30912D01*
X30512Y-169476D01*
X30112Y-169876D01*
X29712D01*
X30112Y-170276D01*
X29712Y-170676D01*
X30112D01*
X30512Y-171076D01*
Y-170676D02*
X30712Y-170476D01*
X30912D01*
X30712Y-170276D01*
X30912Y-170076D01*
X30712D01*
X30512Y-169876D01*
X30312Y-170076D01*
X30112D01*
X30312Y-170276D01*
X30112Y-170476D01*
X30312D01*
X30512Y-170676D01*
X323850Y-241973D02*
X324250Y-241573D01*
X324650D01*
X324250Y-241173D01*
X324650Y-240773D01*
X324250D01*
X323850Y-240373D01*
X323450Y-240773D01*
X323050D01*
X323450Y-241173D01*
X323050Y-241573D01*
X323450D01*
X323850Y-241973D01*
Y-241573D02*
X324050Y-241373D01*
X324250D01*
X324050Y-241173D01*
X324250Y-240973D01*
X324050D01*
X323850Y-240773D01*
X323650Y-240973D01*
X323450D01*
X323650Y-241173D01*
X323450Y-241373D01*
X323650D01*
X323850Y-241573D01*
Y-238005D02*
X324250Y-237605D01*
X324650D01*
X324250Y-237205D01*
X324650Y-236805D01*
X324250D01*
X323850Y-236405D01*
X323450Y-236805D01*
X323050D01*
X323450Y-237205D01*
X323050Y-237605D01*
X323450D01*
X323850Y-238005D01*
Y-237605D02*
X324050Y-237405D01*
X324250D01*
X324050Y-237205D01*
X324250Y-237005D01*
X324050D01*
X323850Y-236805D01*
X323650Y-237005D01*
X323450D01*
X323650Y-237205D01*
X323450Y-237405D01*
X323650D01*
X323850Y-237605D01*
X323819Y-232099D02*
X324219Y-231699D01*
X324619D01*
X324219Y-231299D01*
X324619Y-230899D01*
X324219D01*
X323819Y-230499D01*
X323419Y-230899D01*
X323019D01*
X323419Y-231299D01*
X323019Y-231699D01*
X323419D01*
X323819Y-232099D01*
Y-231699D02*
X324019Y-231499D01*
X324219D01*
X324019Y-231299D01*
X324219Y-231099D01*
X324019D01*
X323819Y-230899D01*
X323619Y-231099D01*
X323419D01*
X323619Y-231299D01*
X323419Y-231499D01*
X323619D01*
X323819Y-231699D01*
X325787Y-230162D02*
X326187Y-229762D01*
X326587D01*
X326187Y-229362D01*
X326587Y-228962D01*
X326187D01*
X325787Y-228562D01*
X325387Y-228962D01*
X324987D01*
X325387Y-229362D01*
X324987Y-229762D01*
X325387D01*
X325787Y-230162D01*
Y-229762D02*
X325987Y-229562D01*
X326187D01*
X325987Y-229362D01*
X326187Y-229162D01*
X325987D01*
X325787Y-228962D01*
X325587Y-229162D01*
X325387D01*
X325587Y-229362D01*
X325387Y-229562D01*
X325587D01*
X325787Y-229762D01*
X323819Y-228162D02*
X324219Y-227762D01*
X324619D01*
X324219Y-227362D01*
X324619Y-226962D01*
X324219D01*
X323819Y-226562D01*
X323419Y-226962D01*
X323019D01*
X323419Y-227362D01*
X323019Y-227762D01*
X323419D01*
X323819Y-228162D01*
Y-227762D02*
X324019Y-227562D01*
X324219D01*
X324019Y-227362D01*
X324219Y-227162D01*
X324019D01*
X323819Y-226962D01*
X323619Y-227162D01*
X323419D01*
X323619Y-227362D01*
X323419Y-227562D01*
X323619D01*
X323819Y-227762D01*
X325787Y-240005D02*
X326187Y-239605D01*
X326587D01*
X326187Y-239205D01*
X326587Y-238805D01*
X326187D01*
X325787Y-238405D01*
X325387Y-238805D01*
X324987D01*
X325387Y-239205D01*
X324987Y-239605D01*
X325387D01*
X325787Y-240005D01*
Y-239605D02*
X325987Y-239405D01*
X326187D01*
X325987Y-239205D01*
X326187Y-239005D01*
X325987D01*
X325787Y-238805D01*
X325587Y-239005D01*
X325387D01*
X325587Y-239205D01*
X325387Y-239405D01*
X325587D01*
X325787Y-239605D01*
X-23622Y-343320D02*
X-23222Y-342920D01*
X-22822D01*
X-23222Y-342520D01*
X-22822Y-342120D01*
X-23222D01*
X-23622Y-341720D01*
X-24022Y-342120D01*
X-24422D01*
X-24022Y-342520D01*
X-24422Y-342920D01*
X-24022D01*
X-23622Y-343320D01*
Y-342920D02*
X-23422Y-342720D01*
X-23222D01*
X-23422Y-342520D01*
X-23222Y-342320D01*
X-23422D01*
X-23622Y-342120D01*
X-23822Y-342320D01*
X-24022D01*
X-23822Y-342520D01*
X-24022Y-342720D01*
X-23822D01*
X-23622Y-342920D01*
X89567Y-141070D02*
X89967Y-140670D01*
X90367D01*
X89967Y-140270D01*
X90367Y-139870D01*
X89967D01*
X89567Y-139470D01*
X89167Y-139870D01*
X88767D01*
X89167Y-140270D01*
X88767Y-140670D01*
X89167D01*
X89567Y-141070D01*
Y-140670D02*
X89767Y-140470D01*
X89967D01*
X89767Y-140270D01*
X89967Y-140070D01*
X89767D01*
X89567Y-139870D01*
X89367Y-140070D01*
X89167D01*
X89367Y-140270D01*
X89167Y-140470D01*
X89367D01*
X89567Y-140670D01*
X87254Y-140429D02*
X87654Y-140029D01*
X88054D01*
X87654Y-139629D01*
X88054Y-139229D01*
X87654D01*
X87254Y-138829D01*
X86854Y-139229D01*
X86454D01*
X86854Y-139629D01*
X86454Y-140029D01*
X86854D01*
X87254Y-140429D01*
Y-140029D02*
X87454Y-139829D01*
X87654D01*
X87454Y-139629D01*
X87654Y-139429D01*
X87454D01*
X87254Y-139229D01*
X87054Y-139429D01*
X86854D01*
X87054Y-139629D01*
X86854Y-139829D01*
X87054D01*
X87254Y-140029D01*
X119095Y-130847D02*
X119494Y-130447D01*
X119895D01*
X119494Y-130047D01*
X119895Y-129647D01*
X119494D01*
X119095Y-129247D01*
X118694Y-129647D01*
X118295D01*
X118694Y-130047D01*
X118295Y-130447D01*
X118694D01*
X119095Y-130847D01*
Y-130447D02*
X119295Y-130247D01*
X119494D01*
X119295Y-130047D01*
X119494Y-129847D01*
X119295D01*
X119095Y-129647D01*
X118895Y-129847D01*
X118694D01*
X118895Y-130047D01*
X118694Y-130247D01*
X118895D01*
X119095Y-130447D01*
X117126Y-132847D02*
X117526Y-132447D01*
X117926D01*
X117526Y-132047D01*
X117926Y-131647D01*
X117526D01*
X117126Y-131247D01*
X116726Y-131647D01*
X116326D01*
X116726Y-132047D01*
X116326Y-132447D01*
X116726D01*
X117126Y-132847D01*
Y-132447D02*
X117326Y-132247D01*
X117526D01*
X117326Y-132047D01*
X117526Y-131847D01*
X117326D01*
X117126Y-131647D01*
X116926Y-131847D01*
X116726D01*
X116926Y-132047D01*
X116726Y-132247D01*
X116926D01*
X117126Y-132447D01*
X107346Y-111036D02*
X107747Y-110636D01*
X108147D01*
X107747Y-110236D01*
X108147Y-109836D01*
X107747D01*
X107346Y-109436D01*
X106947Y-109836D01*
X106546D01*
X106947Y-110236D01*
X106546Y-110636D01*
X106947D01*
X107346Y-111036D01*
Y-110636D02*
X107546Y-110436D01*
X107747D01*
X107546Y-110236D01*
X107747Y-110036D01*
X107546D01*
X107346Y-109836D01*
X107147Y-110036D01*
X106947D01*
X107147Y-110236D01*
X106947Y-110436D01*
X107147D01*
X107346Y-110636D01*
X105347Y-113005D02*
X105746Y-112605D01*
X106147D01*
X105746Y-112205D01*
X106147Y-111805D01*
X105746D01*
X105347Y-111405D01*
X104946Y-111805D01*
X104546D01*
X104946Y-112205D01*
X104546Y-112605D01*
X104946D01*
X105347Y-113005D01*
Y-112605D02*
X105546Y-112405D01*
X105746D01*
X105546Y-112205D01*
X105746Y-112005D01*
X105546D01*
X105347Y-111805D01*
X105147Y-112005D01*
X104946D01*
X105147Y-112205D01*
X104946Y-112405D01*
X105147D01*
X105347Y-112605D01*
X99347Y-111036D02*
X99747Y-110636D01*
X100146D01*
X99747Y-110236D01*
X100146Y-109836D01*
X99747D01*
X99347Y-109436D01*
X98946Y-109836D01*
X98546D01*
X98946Y-110236D01*
X98546Y-110636D01*
X98946D01*
X99347Y-111036D01*
Y-110636D02*
X99546Y-110436D01*
X99747D01*
X99546Y-110236D01*
X99747Y-110036D01*
X99546D01*
X99347Y-109836D01*
X99146Y-110036D01*
X98946D01*
X99146Y-110236D01*
X98946Y-110436D01*
X99146D01*
X99347Y-110636D01*
X109409Y-113036D02*
X109810Y-112636D01*
X110210D01*
X109810Y-112236D01*
X110210Y-111836D01*
X109810D01*
X109409Y-111436D01*
X109010Y-111836D01*
X108609D01*
X109010Y-112236D01*
X108609Y-112636D01*
X109010D01*
X109409Y-113036D01*
Y-112636D02*
X109609Y-112436D01*
X109810D01*
X109609Y-112236D01*
X109810Y-112036D01*
X109609D01*
X109409Y-111836D01*
X109210Y-112036D01*
X109010D01*
X109210Y-112236D01*
X109010Y-112436D01*
X109210D01*
X109409Y-112636D01*
X119095Y-122847D02*
X119494Y-122447D01*
X119895D01*
X119494Y-122047D01*
X119895Y-121647D01*
X119494D01*
X119095Y-121247D01*
X118694Y-121647D01*
X118295D01*
X118694Y-122047D01*
X118295Y-122447D01*
X118694D01*
X119095Y-122847D01*
Y-122447D02*
X119295Y-122247D01*
X119494D01*
X119295Y-122047D01*
X119494Y-121847D01*
X119295D01*
X119095Y-121647D01*
X118895Y-121847D01*
X118694D01*
X118895Y-122047D01*
X118694Y-122247D01*
X118895D01*
X119095Y-122447D01*
X-23622Y-230131D02*
X-23222Y-229731D01*
X-22822D01*
X-23222Y-229331D01*
X-22822Y-228931D01*
X-23222D01*
X-23622Y-228531D01*
X-24022Y-228931D01*
X-24422D01*
X-24022Y-229331D01*
X-24422Y-229731D01*
X-24022D01*
X-23622Y-230131D01*
Y-229731D02*
X-23422Y-229531D01*
X-23222D01*
X-23422Y-229331D01*
X-23222Y-229131D01*
X-23422D01*
X-23622Y-228931D01*
X-23822Y-229131D01*
X-24022D01*
X-23822Y-229331D01*
X-24022Y-229531D01*
X-23822D01*
X-23622Y-229731D01*
Y-234068D02*
X-23222Y-233668D01*
X-22822D01*
X-23222Y-233268D01*
X-22822Y-232868D01*
X-23222D01*
X-23622Y-232468D01*
X-24022Y-232868D01*
X-24422D01*
X-24022Y-233268D01*
X-24422Y-233668D01*
X-24022D01*
X-23622Y-234068D01*
Y-233668D02*
X-23422Y-233468D01*
X-23222D01*
X-23422Y-233268D01*
X-23222Y-233068D01*
X-23422D01*
X-23622Y-232868D01*
X-23822Y-233068D01*
X-24022D01*
X-23822Y-233268D01*
X-24022Y-233468D01*
X-23822D01*
X-23622Y-233668D01*
Y-238005D02*
X-23222Y-237605D01*
X-22822D01*
X-23222Y-237205D01*
X-22822Y-236805D01*
X-23222D01*
X-23622Y-236405D01*
X-24022Y-236805D01*
X-24422D01*
X-24022Y-237205D01*
X-24422Y-237605D01*
X-24022D01*
X-23622Y-238005D01*
Y-237605D02*
X-23422Y-237405D01*
X-23222D01*
X-23422Y-237205D01*
X-23222Y-237005D01*
X-23422D01*
X-23622Y-236805D01*
X-23822Y-237005D01*
X-24022D01*
X-23822Y-237205D01*
X-24022Y-237405D01*
X-23822D01*
X-23622Y-237605D01*
Y-241942D02*
X-23222Y-241542D01*
X-22822D01*
X-23222Y-241142D01*
X-22822Y-240742D01*
X-23222D01*
X-23622Y-240342D01*
X-24022Y-240742D01*
X-24422D01*
X-24022Y-241142D01*
X-24422Y-241542D01*
X-24022D01*
X-23622Y-241942D01*
Y-241542D02*
X-23422Y-241342D01*
X-23222D01*
X-23422Y-241142D01*
X-23222Y-240942D01*
X-23422D01*
X-23622Y-240742D01*
X-23822Y-240942D01*
X-24022D01*
X-23822Y-241142D01*
X-24022Y-241342D01*
X-23822D01*
X-23622Y-241542D01*
Y-283280D02*
X-23222Y-282880D01*
X-22822D01*
X-23222Y-282480D01*
X-22822Y-282080D01*
X-23222D01*
X-23622Y-281680D01*
X-24022Y-282080D01*
X-24422D01*
X-24022Y-282480D01*
X-24422Y-282880D01*
X-24022D01*
X-23622Y-283280D01*
Y-282880D02*
X-23422Y-282680D01*
X-23222D01*
X-23422Y-282480D01*
X-23222Y-282280D01*
X-23422D01*
X-23622Y-282080D01*
X-23822Y-282280D01*
X-24022D01*
X-23822Y-282480D01*
X-24022Y-282680D01*
X-23822D01*
X-23622Y-282880D01*
Y-287217D02*
X-23222Y-286817D01*
X-22822D01*
X-23222Y-286417D01*
X-22822Y-286017D01*
X-23222D01*
X-23622Y-285617D01*
X-24022Y-286017D01*
X-24422D01*
X-24022Y-286417D01*
X-24422Y-286817D01*
X-24022D01*
X-23622Y-287217D01*
Y-286817D02*
X-23422Y-286617D01*
X-23222D01*
X-23422Y-286417D01*
X-23222Y-286217D01*
X-23422D01*
X-23622Y-286017D01*
X-23822Y-286217D01*
X-24022D01*
X-23822Y-286417D01*
X-24022Y-286617D01*
X-23822D01*
X-23622Y-286817D01*
Y-291154D02*
X-23222Y-290754D01*
X-22822D01*
X-23222Y-290354D01*
X-22822Y-289954D01*
X-23222D01*
X-23622Y-289554D01*
X-24022Y-289954D01*
X-24422D01*
X-24022Y-290354D01*
X-24422Y-290754D01*
X-24022D01*
X-23622Y-291154D01*
Y-290754D02*
X-23422Y-290554D01*
X-23222D01*
X-23422Y-290354D01*
X-23222Y-290154D01*
X-23422D01*
X-23622Y-289954D01*
X-23822Y-290154D01*
X-24022D01*
X-23822Y-290354D01*
X-24022Y-290554D01*
X-23822D01*
X-23622Y-290754D01*
Y-295091D02*
X-23222Y-294691D01*
X-22822D01*
X-23222Y-294291D01*
X-22822Y-293891D01*
X-23222D01*
X-23622Y-293491D01*
X-24022Y-293891D01*
X-24422D01*
X-24022Y-294291D01*
X-24422Y-294691D01*
X-24022D01*
X-23622Y-295091D01*
Y-294691D02*
X-23422Y-294491D01*
X-23222D01*
X-23422Y-294291D01*
X-23222Y-294091D01*
X-23422D01*
X-23622Y-293891D01*
X-23822Y-294091D01*
X-24022D01*
X-23822Y-294291D01*
X-24022Y-294491D01*
X-23822D01*
X-23622Y-294691D01*
Y-336430D02*
X-23222Y-336030D01*
X-22822D01*
X-23222Y-335630D01*
X-22822Y-335230D01*
X-23222D01*
X-23622Y-334830D01*
X-24022Y-335230D01*
X-24422D01*
X-24022Y-335630D01*
X-24422Y-336030D01*
X-24022D01*
X-23622Y-336430D01*
Y-336030D02*
X-23422Y-335830D01*
X-23222D01*
X-23422Y-335630D01*
X-23222Y-335430D01*
X-23422D01*
X-23622Y-335230D01*
X-23822Y-335430D01*
X-24022D01*
X-23822Y-335630D01*
X-24022Y-335830D01*
X-23822D01*
X-23622Y-336030D01*
Y-340367D02*
X-23222Y-339967D01*
X-22822D01*
X-23222Y-339567D01*
X-22822Y-339167D01*
X-23222D01*
X-23622Y-338767D01*
X-24022Y-339167D01*
X-24422D01*
X-24022Y-339567D01*
X-24422Y-339967D01*
X-24022D01*
X-23622Y-340367D01*
Y-339967D02*
X-23422Y-339767D01*
X-23222D01*
X-23422Y-339567D01*
X-23222Y-339367D01*
X-23422D01*
X-23622Y-339167D01*
X-23822Y-339367D01*
X-24022D01*
X-23822Y-339567D01*
X-24022Y-339767D01*
X-23822D01*
X-23622Y-339967D01*
Y-347257D02*
X-23222Y-346857D01*
X-22822D01*
X-23222Y-346457D01*
X-22822Y-346057D01*
X-23222D01*
X-23622Y-345657D01*
X-24022Y-346057D01*
X-24422D01*
X-24022Y-346457D01*
X-24422Y-346857D01*
X-24022D01*
X-23622Y-347257D01*
Y-346857D02*
X-23422Y-346657D01*
X-23222D01*
X-23422Y-346457D01*
X-23222Y-346257D01*
X-23422D01*
X-23622Y-346057D01*
X-23822Y-346257D01*
X-24022D01*
X-23822Y-346457D01*
X-24022Y-346657D01*
X-23822D01*
X-23622Y-346857D01*
X107409Y-142532D02*
X107809Y-142132D01*
X108209D01*
X107809Y-141732D01*
X108209Y-141332D01*
X107809D01*
X107409Y-140932D01*
X107009Y-141332D01*
X106609D01*
X107009Y-141732D01*
X106609Y-142132D01*
X107009D01*
X107409Y-142532D01*
Y-142132D02*
X107609Y-141932D01*
X107809D01*
X107609Y-141732D01*
X107809Y-141532D01*
X107609D01*
X107409Y-141332D01*
X107209Y-141532D01*
X107009D01*
X107209Y-141732D01*
X107009Y-141932D01*
X107209D01*
X107409Y-142132D01*
X99410Y-142532D02*
X99809Y-142132D01*
X100209D01*
X99809Y-141732D01*
X100209Y-141332D01*
X99809D01*
X99410Y-140932D01*
X99010Y-141332D01*
X98610D01*
X99010Y-141732D01*
X98610Y-142132D01*
X99010D01*
X99410Y-142532D01*
Y-142132D02*
X99610Y-141932D01*
X99809D01*
X99610Y-141732D01*
X99809Y-141532D01*
X99610D01*
X99410Y-141332D01*
X99209Y-141532D01*
X99010D01*
X99209Y-141732D01*
X99010Y-141932D01*
X99209D01*
X99410Y-142132D01*
X-23622Y-71666D02*
X-23222Y-71266D01*
X-22822D01*
X-23222Y-70866D01*
X-22822Y-70466D01*
X-23222D01*
X-23622Y-70066D01*
X-24022Y-70466D01*
X-24422D01*
X-24022Y-70866D01*
X-24422Y-71266D01*
X-24022D01*
X-23622Y-71666D01*
Y-71266D02*
X-23422Y-71066D01*
X-23222D01*
X-23422Y-70866D01*
X-23222Y-70666D01*
X-23422D01*
X-23622Y-70466D01*
X-23822Y-70666D01*
X-24022D01*
X-23822Y-70866D01*
X-24022Y-71066D01*
X-23822D01*
X-23622Y-71266D01*
Y-67729D02*
X-23222Y-67329D01*
X-22822D01*
X-23222Y-66929D01*
X-22822Y-66529D01*
X-23222D01*
X-23622Y-66129D01*
X-24022Y-66529D01*
X-24422D01*
X-24022Y-66929D01*
X-24422Y-67329D01*
X-24022D01*
X-23622Y-67729D01*
Y-67329D02*
X-23422Y-67129D01*
X-23222D01*
X-23422Y-66929D01*
X-23222Y-66729D01*
X-23422D01*
X-23622Y-66529D01*
X-23822Y-66729D01*
X-24022D01*
X-23822Y-66929D01*
X-24022Y-67129D01*
X-23822D01*
X-23622Y-67329D01*
Y-63792D02*
X-23222Y-63392D01*
X-22822D01*
X-23222Y-62992D01*
X-22822Y-62592D01*
X-23222D01*
X-23622Y-62192D01*
X-24022Y-62592D01*
X-24422D01*
X-24022Y-62992D01*
X-24422Y-63392D01*
X-24022D01*
X-23622Y-63792D01*
Y-63392D02*
X-23422Y-63192D01*
X-23222D01*
X-23422Y-62992D01*
X-23222Y-62792D01*
X-23422D01*
X-23622Y-62592D01*
X-23822Y-62792D01*
X-24022D01*
X-23822Y-62992D01*
X-24022Y-63192D01*
X-23822D01*
X-23622Y-63392D01*
Y-60839D02*
X-23222Y-60439D01*
X-22822D01*
X-23222Y-60039D01*
X-22822Y-59639D01*
X-23222D01*
X-23622Y-59239D01*
X-24022Y-59639D01*
X-24422D01*
X-24022Y-60039D01*
X-24422Y-60439D01*
X-24022D01*
X-23622Y-60839D01*
Y-60439D02*
X-23422Y-60239D01*
X-23222D01*
X-23422Y-60039D01*
X-23222Y-59839D01*
X-23422D01*
X-23622Y-59639D01*
X-23822Y-59839D01*
X-24022D01*
X-23822Y-60039D01*
X-24022Y-60239D01*
X-23822D01*
X-23622Y-60439D01*
Y-103162D02*
X-23222Y-102762D01*
X-22822D01*
X-23222Y-102362D01*
X-22822Y-101962D01*
X-23222D01*
X-23622Y-101562D01*
X-24022Y-101962D01*
X-24422D01*
X-24022Y-102362D01*
X-24422Y-102762D01*
X-24022D01*
X-23622Y-103162D01*
Y-102762D02*
X-23422Y-102562D01*
X-23222D01*
X-23422Y-102362D01*
X-23222Y-102162D01*
X-23422D01*
X-23622Y-101962D01*
X-23822Y-102162D01*
X-24022D01*
X-23822Y-102362D01*
X-24022Y-102562D01*
X-23822D01*
X-23622Y-102762D01*
Y-107099D02*
X-23222Y-106699D01*
X-22822D01*
X-23222Y-106299D01*
X-22822Y-105899D01*
X-23222D01*
X-23622Y-105499D01*
X-24022Y-105899D01*
X-24422D01*
X-24022Y-106299D01*
X-24422Y-106699D01*
X-24022D01*
X-23622Y-107099D01*
Y-106699D02*
X-23422Y-106499D01*
X-23222D01*
X-23422Y-106299D01*
X-23222Y-106099D01*
X-23422D01*
X-23622Y-105899D01*
X-23822Y-106099D01*
X-24022D01*
X-23822Y-106299D01*
X-24022Y-106499D01*
X-23822D01*
X-23622Y-106699D01*
Y-111036D02*
X-23222Y-110636D01*
X-22822D01*
X-23222Y-110236D01*
X-22822Y-109836D01*
X-23222D01*
X-23622Y-109436D01*
X-24022Y-109836D01*
X-24422D01*
X-24022Y-110236D01*
X-24422Y-110636D01*
X-24022D01*
X-23622Y-111036D01*
Y-110636D02*
X-23422Y-110436D01*
X-23222D01*
X-23422Y-110236D01*
X-23222Y-110036D01*
X-23422D01*
X-23622Y-109836D01*
X-23822Y-110036D01*
X-24022D01*
X-23822Y-110236D01*
X-24022Y-110436D01*
X-23822D01*
X-23622Y-110636D01*
Y-114973D02*
X-23222Y-114573D01*
X-22822D01*
X-23222Y-114173D01*
X-22822Y-113773D01*
X-23222D01*
X-23622Y-113373D01*
X-24022Y-113773D01*
X-24422D01*
X-24022Y-114173D01*
X-24422Y-114573D01*
X-24022D01*
X-23622Y-114973D01*
Y-114573D02*
X-23422Y-114373D01*
X-23222D01*
X-23422Y-114173D01*
X-23222Y-113973D01*
X-23422D01*
X-23622Y-113773D01*
X-23822Y-113973D01*
X-24022D01*
X-23822Y-114173D01*
X-24022Y-114373D01*
X-23822D01*
X-23622Y-114573D01*
Y-188792D02*
X-23222Y-188392D01*
X-22822D01*
X-23222Y-187992D01*
X-22822Y-187592D01*
X-23222D01*
X-23622Y-187192D01*
X-24022Y-187592D01*
X-24422D01*
X-24022Y-187992D01*
X-24422Y-188392D01*
X-24022D01*
X-23622Y-188792D01*
Y-188392D02*
X-23422Y-188192D01*
X-23222D01*
X-23422Y-187992D01*
X-23222Y-187792D01*
X-23422D01*
X-23622Y-187592D01*
X-23822Y-187792D01*
X-24022D01*
X-23822Y-187992D01*
X-24022Y-188192D01*
X-23822D01*
X-23622Y-188392D01*
Y-184855D02*
X-23222Y-184455D01*
X-22822D01*
X-23222Y-184055D01*
X-22822Y-183655D01*
X-23222D01*
X-23622Y-183255D01*
X-24022Y-183655D01*
X-24422D01*
X-24022Y-184055D01*
X-24422Y-184455D01*
X-24022D01*
X-23622Y-184855D01*
Y-184455D02*
X-23422Y-184255D01*
X-23222D01*
X-23422Y-184055D01*
X-23222Y-183855D01*
X-23422D01*
X-23622Y-183655D01*
X-23822Y-183855D01*
X-24022D01*
X-23822Y-184055D01*
X-24022Y-184255D01*
X-23822D01*
X-23622Y-184455D01*
Y-181902D02*
X-23222Y-181502D01*
X-22822D01*
X-23222Y-181102D01*
X-22822Y-180702D01*
X-23222D01*
X-23622Y-180302D01*
X-24022Y-180702D01*
X-24422D01*
X-24022Y-181102D01*
X-24422Y-181502D01*
X-24022D01*
X-23622Y-181902D01*
Y-181502D02*
X-23422Y-181302D01*
X-23222D01*
X-23422Y-181102D01*
X-23222Y-180902D01*
X-23422D01*
X-23622Y-180702D01*
X-23822Y-180902D01*
X-24022D01*
X-23822Y-181102D01*
X-24022Y-181302D01*
X-23822D01*
X-23622Y-181502D01*
Y-177965D02*
X-23222Y-177565D01*
X-22822D01*
X-23222Y-177165D01*
X-22822Y-176765D01*
X-23222D01*
X-23622Y-176365D01*
X-24022Y-176765D01*
X-24422D01*
X-24022Y-177165D01*
X-24422Y-177565D01*
X-24022D01*
X-23622Y-177965D01*
Y-177565D02*
X-23422Y-177365D01*
X-23222D01*
X-23422Y-177165D01*
X-23222Y-176965D01*
X-23422D01*
X-23622Y-176765D01*
X-23822Y-176965D01*
X-24022D01*
X-23822Y-177165D01*
X-24022Y-177365D01*
X-23822D01*
X-23622Y-177565D01*
X117126Y-128847D02*
X117526Y-128447D01*
X117926D01*
X117526Y-128047D01*
X117926Y-127647D01*
X117526D01*
X117126Y-127247D01*
X116726Y-127647D01*
X116326D01*
X116726Y-128047D01*
X116326Y-128447D01*
X116726D01*
X117126Y-128847D01*
Y-128447D02*
X117326Y-128247D01*
X117526D01*
X117326Y-128047D01*
X117526Y-127847D01*
X117326D01*
X117126Y-127647D01*
X116926Y-127847D01*
X116726D01*
X116926Y-128047D01*
X116726Y-128247D01*
X116926D01*
X117126Y-128447D01*
Y-124847D02*
X117526Y-124447D01*
X117926D01*
X117526Y-124047D01*
X117926Y-123647D01*
X117526D01*
X117126Y-123247D01*
X116726Y-123647D01*
X116326D01*
X116726Y-124047D01*
X116326Y-124447D01*
X116726D01*
X117126Y-124847D01*
Y-124447D02*
X117326Y-124247D01*
X117526D01*
X117326Y-124047D01*
X117526Y-123847D01*
X117326D01*
X117126Y-123647D01*
X116926Y-123847D01*
X116726D01*
X116926Y-124047D01*
X116726Y-124247D01*
X116926D01*
X117126Y-124447D01*
Y-120721D02*
X117526Y-120321D01*
X117926D01*
X117526Y-119921D01*
X117926Y-119521D01*
X117526D01*
X117126Y-119121D01*
X116726Y-119521D01*
X116326D01*
X116726Y-119921D01*
X116326Y-120321D01*
X116726D01*
X117126Y-120721D01*
Y-120321D02*
X117326Y-120121D01*
X117526D01*
X117326Y-119921D01*
X117526Y-119721D01*
X117326D01*
X117126Y-119521D01*
X116926Y-119721D01*
X116726D01*
X116926Y-119921D01*
X116726Y-120121D01*
X116926D01*
X117126Y-120321D01*
X101284Y-113005D02*
X101683Y-112605D01*
X102084D01*
X101683Y-112205D01*
X102084Y-111805D01*
X101683D01*
X101284Y-111405D01*
X100883Y-111805D01*
X100484D01*
X100883Y-112205D01*
X100484Y-112605D01*
X100883D01*
X101284Y-113005D01*
Y-112605D02*
X101484Y-112405D01*
X101683D01*
X101484Y-112205D01*
X101683Y-112005D01*
X101484D01*
X101284Y-111805D01*
X101084Y-112005D01*
X100883D01*
X101084Y-112205D01*
X100883Y-112405D01*
X101084D01*
X101284Y-112605D01*
X97284Y-113005D02*
X97684Y-112605D01*
X98084D01*
X97684Y-112205D01*
X98084Y-111805D01*
X97684D01*
X97284Y-111405D01*
X96883Y-111805D01*
X96483D01*
X96883Y-112205D01*
X96483Y-112605D01*
X96883D01*
X97284Y-113005D01*
Y-112605D02*
X97483Y-112405D01*
X97684D01*
X97483Y-112205D01*
X97684Y-112005D01*
X97483D01*
X97284Y-111805D01*
X97083Y-112005D01*
X96883D01*
X97083Y-112205D01*
X96883Y-112405D01*
X97083D01*
X97284Y-112605D01*
X651545Y-93108D02*
Y-95108D01*
X652545D01*
X652878Y-94775D01*
Y-94441D01*
X652545Y-94108D01*
X651545D01*
X652545D01*
X652878Y-93775D01*
Y-93442D01*
X652545Y-93108D01*
X651545D01*
X413356Y9254D02*
Y7254D01*
X414356D01*
X414689Y7588D01*
Y7921D01*
X414356Y8254D01*
X413356D01*
X414356D01*
X414689Y8587D01*
Y8920D01*
X414356Y9254D01*
X413356D01*
Y-93108D02*
Y-95108D01*
X414356D01*
X414689Y-94775D01*
Y-94441D01*
X414356Y-94108D01*
X413356D01*
X414356D01*
X414689Y-93775D01*
Y-93442D01*
X414356Y-93108D01*
X413356D01*
X651545Y9254D02*
Y7254D01*
X652545D01*
X652878Y7588D01*
Y7921D01*
X652545Y8254D01*
X651545D01*
X652545D01*
X652878Y8587D01*
Y8920D01*
X652545Y9254D01*
X651545D01*
X71880Y9411D02*
Y7412D01*
X72880D01*
X73213Y7745D01*
Y8078D01*
X72880Y8411D01*
X71880D01*
X72880D01*
X73213Y8745D01*
Y9078D01*
X72880Y9411D01*
X71880D01*
X310069Y-92951D02*
Y-94950D01*
X311069D01*
X311402Y-94617D01*
Y-94284D01*
X311069Y-93951D01*
X310069D01*
X311069D01*
X311402Y-93618D01*
Y-93284D01*
X311069Y-92951D01*
X310069D01*
Y9411D02*
Y7412D01*
X311069D01*
X311402Y7745D01*
Y8078D01*
X311069Y8411D01*
X310069D01*
X311069D01*
X311402Y8745D01*
Y9078D01*
X311069Y9411D01*
X310069D01*
X71880Y-92951D02*
Y-94950D01*
X72880D01*
X73213Y-94617D01*
Y-94284D01*
X72880Y-93951D01*
X71880D01*
X72880D01*
X73213Y-93618D01*
Y-93284D01*
X72880Y-92951D01*
X71880D01*
X100349Y-119987D02*
X100015Y-119654D01*
X99349D01*
X99016Y-119987D01*
Y-121320D01*
X99349Y-121653D01*
X100015D01*
X100349Y-121320D01*
X104679Y-119987D02*
X104346Y-119654D01*
X103680D01*
X103347Y-119987D01*
Y-121320D01*
X103680Y-121653D01*
X104346D01*
X104679Y-121320D01*
X109010Y-119987D02*
X108677Y-119654D01*
X108010D01*
X107677Y-119987D01*
Y-121320D01*
X108010Y-121653D01*
X108677D01*
X109010Y-121320D01*
X100349Y-124318D02*
X100015Y-123985D01*
X99349D01*
X99016Y-124318D01*
Y-125651D01*
X99349Y-125984D01*
X100015D01*
X100349Y-125651D01*
X104679Y-124318D02*
X104346Y-123985D01*
X103680D01*
X103347Y-124318D01*
Y-125651D01*
X103680Y-125984D01*
X104346D01*
X104679Y-125651D01*
X109010Y-124318D02*
X108677Y-123985D01*
X108010D01*
X107677Y-124318D01*
Y-125651D01*
X108010Y-125984D01*
X108677D01*
X109010Y-125651D01*
X100349Y-128649D02*
X100015Y-128316D01*
X99349D01*
X99016Y-128649D01*
Y-129982D01*
X99349Y-130315D01*
X100015D01*
X100349Y-129982D01*
X104679Y-128649D02*
X104346Y-128316D01*
X103680D01*
X103347Y-128649D01*
Y-129982D01*
X103680Y-130315D01*
X104346D01*
X104679Y-129982D01*
X109010Y-128649D02*
X108677Y-128316D01*
X108010D01*
X107677Y-128649D01*
Y-129982D01*
X108010Y-130315D01*
X108677D01*
X109010Y-129982D01*
X544291Y-196518D02*
X544691Y-196118D01*
X545091D01*
X544691Y-195718D01*
X545091Y-195318D01*
X544691D01*
X544291Y-194918D01*
X543891Y-195318D01*
X543491D01*
X543891Y-195718D01*
X543491Y-196118D01*
X543891D01*
X544291Y-196518D01*
Y-196118D02*
X544491Y-195918D01*
X544691D01*
X544491Y-195718D01*
X544691Y-195518D01*
X544491D01*
X544291Y-195318D01*
X544091Y-195518D01*
X543891D01*
X544091Y-195718D01*
X543891Y-195918D01*
X544091D01*
X544291Y-196118D01*
X469521Y-138415D02*
X469921Y-138015D01*
X470321D01*
X469921Y-137615D01*
X470321Y-137215D01*
X469921D01*
X469521Y-136815D01*
X469121Y-137215D01*
X468721D01*
X469121Y-137615D01*
X468721Y-138015D01*
X469121D01*
X469521Y-138415D01*
Y-138015D02*
X469721Y-137815D01*
X469921D01*
X469721Y-137615D01*
X469921Y-137415D01*
X469721D01*
X469521Y-137215D01*
X469321Y-137415D01*
X469121D01*
X469321Y-137615D01*
X469121Y-137815D01*
X469321D01*
X469521Y-138015D01*
X533878Y-118516D02*
X534278Y-118116D01*
X534678D01*
X534278Y-117716D01*
X534678Y-117316D01*
X534278D01*
X533878Y-116916D01*
X533478Y-117316D01*
X533078D01*
X533478Y-117716D01*
X533078Y-118116D01*
X533478D01*
X533878Y-118516D01*
Y-118116D02*
X534078Y-117916D01*
X534278D01*
X534078Y-117716D01*
X534278Y-117516D01*
X534078D01*
X533878Y-117316D01*
X533678Y-117516D01*
X533478D01*
X533678Y-117716D01*
X533478Y-117916D01*
X533678D01*
X533878Y-118116D01*
X524606Y-126636D02*
X525006Y-126236D01*
X525406D01*
X525006Y-125836D01*
X525406Y-125436D01*
X525006D01*
X524606Y-125036D01*
X524206Y-125436D01*
X523806D01*
X524206Y-125836D01*
X523806Y-126236D01*
X524206D01*
X524606Y-126636D01*
Y-126236D02*
X524806Y-126036D01*
X525006D01*
X524806Y-125836D01*
X525006Y-125636D01*
X524806D01*
X524606Y-125436D01*
X524406Y-125636D01*
X524206D01*
X524406Y-125836D01*
X524206Y-126036D01*
X524406D01*
X524606Y-126236D01*
X524557Y-129540D02*
X524957Y-129140D01*
X525357D01*
X524957Y-128740D01*
X525357Y-128340D01*
X524957D01*
X524557Y-127940D01*
X524157Y-128340D01*
X523757D01*
X524157Y-128740D01*
X523757Y-129140D01*
X524157D01*
X524557Y-129540D01*
Y-129140D02*
X524757Y-128940D01*
X524957D01*
X524757Y-128740D01*
X524957Y-128540D01*
X524757D01*
X524557Y-128340D01*
X524357Y-128540D01*
X524157D01*
X524357Y-128740D01*
X524157Y-128940D01*
X524357D01*
X524557Y-129140D01*
X651557Y-65106D02*
X651957Y-64706D01*
X652357D01*
X651957Y-64306D01*
X652357Y-63906D01*
X651957D01*
X651557Y-63506D01*
X651157Y-63906D01*
X650757D01*
X651157Y-64306D01*
X650757Y-64706D01*
X651157D01*
X651557Y-65106D01*
Y-64706D02*
X651757Y-64506D01*
X651957D01*
X651757Y-64306D01*
X651957Y-64106D01*
X651757D01*
X651557Y-63906D01*
X651357Y-64106D01*
X651157D01*
X651357Y-64306D01*
X651157Y-64506D01*
X651357D01*
X651557Y-64706D01*
X450850Y-174927D02*
X451250Y-174527D01*
X451650D01*
X451250Y-174127D01*
X451650Y-173727D01*
X451250D01*
X450850Y-173327D01*
X450450Y-173727D01*
X450050D01*
X450450Y-174127D01*
X450050Y-174527D01*
X450450D01*
X450850Y-174927D01*
Y-174527D02*
X451050Y-174327D01*
X451250D01*
X451050Y-174127D01*
X451250Y-173927D01*
X451050D01*
X450850Y-173727D01*
X450650Y-173927D01*
X450450D01*
X450650Y-174127D01*
X450450Y-174327D01*
X450650D01*
X450850Y-174527D01*
X512795Y-105014D02*
X513195Y-104614D01*
X513595D01*
X513195Y-104214D01*
X513595Y-103814D01*
X513195D01*
X512795Y-103414D01*
X512395Y-103814D01*
X511995D01*
X512395Y-104214D01*
X511995Y-104614D01*
X512395D01*
X512795Y-105014D01*
Y-104614D02*
X512995Y-104414D01*
X513195D01*
X512995Y-104214D01*
X513195Y-104014D01*
X512995D01*
X512795Y-103814D01*
X512595Y-104014D01*
X512395D01*
X512595Y-104214D01*
X512395Y-104414D01*
X512595D01*
X512795Y-104614D01*
X320866Y-273290D02*
X321266Y-272890D01*
X321666D01*
X321266Y-272490D01*
X321666Y-272090D01*
X321266D01*
X320866Y-271690D01*
X320466Y-272090D01*
X320066D01*
X320466Y-272490D01*
X320066Y-272890D01*
X320466D01*
X320866Y-273290D01*
Y-272890D02*
X321066Y-272690D01*
X321266D01*
X321066Y-272490D01*
X321266Y-272290D01*
X321066D01*
X320866Y-272090D01*
X320666Y-272290D01*
X320466D01*
X320666Y-272490D01*
X320466Y-272690D01*
X320666D01*
X320866Y-272890D01*
X463551Y-116825D02*
X463951Y-116425D01*
X464351D01*
X463951Y-116025D01*
X464351Y-115625D01*
X463951D01*
X463551Y-115225D01*
X463151Y-115625D01*
X462751D01*
X463151Y-116025D01*
X462751Y-116425D01*
X463151D01*
X463551Y-116825D01*
Y-116425D02*
X463751Y-116225D01*
X463951D01*
X463751Y-116025D01*
X463951Y-115825D01*
X463751D01*
X463551Y-115625D01*
X463351Y-115825D01*
X463151D01*
X463351Y-116025D01*
X463151Y-116225D01*
X463351D01*
X463551Y-116425D01*
X658465Y-38447D02*
X658865Y-38047D01*
X659265D01*
X658865Y-37647D01*
X659265Y-37247D01*
X658865D01*
X658465Y-36847D01*
X658065Y-37247D01*
X657665D01*
X658065Y-37647D01*
X657665Y-38047D01*
X658065D01*
X658465Y-38447D01*
Y-38047D02*
X658665Y-37847D01*
X658865D01*
X658665Y-37647D01*
X658865Y-37447D01*
X658665D01*
X658465Y-37247D01*
X658265Y-37447D01*
X658065D01*
X658265Y-37647D01*
X658065Y-37847D01*
X658265D01*
X658465Y-38047D01*
Y-30573D02*
X658865Y-30173D01*
X659265D01*
X658865Y-29773D01*
X659265Y-29373D01*
X658865D01*
X658465Y-28973D01*
X658065Y-29373D01*
X657665D01*
X658065Y-29773D01*
X657665Y-30173D01*
X658065D01*
X658465Y-30573D01*
Y-30173D02*
X658665Y-29973D01*
X658865D01*
X658665Y-29773D01*
X658865Y-29573D01*
X658665D01*
X658465Y-29373D01*
X658265Y-29573D01*
X658065D01*
X658265Y-29773D01*
X658065Y-29973D01*
X658265D01*
X658465Y-30173D01*
X625000Y-22699D02*
X625400Y-22299D01*
X625800D01*
X625400Y-21899D01*
X625800Y-21499D01*
X625400D01*
X625000Y-21099D01*
X624600Y-21499D01*
X624200D01*
X624600Y-21899D01*
X624200Y-22299D01*
X624600D01*
X625000Y-22699D01*
Y-22299D02*
X625200Y-22099D01*
X625400D01*
X625200Y-21899D01*
X625400Y-21699D01*
X625200D01*
X625000Y-21499D01*
X624800Y-21699D01*
X624600D01*
X624800Y-21899D01*
X624600Y-22099D01*
X624800D01*
X625000Y-22299D01*
X190354Y-378211D02*
X190754Y-377811D01*
X191154D01*
X190754Y-377411D01*
X191154Y-377011D01*
X190754D01*
X190354Y-376611D01*
X189954Y-377011D01*
X189554D01*
X189954Y-377411D01*
X189554Y-377811D01*
X189954D01*
X190354Y-378211D01*
Y-377811D02*
X190554Y-377611D01*
X190754D01*
X190554Y-377411D01*
X190754Y-377211D01*
X190554D01*
X190354Y-377011D01*
X190154Y-377211D01*
X189954D01*
X190154Y-377411D01*
X189954Y-377611D01*
X190154D01*
X190354Y-377811D01*
X412339Y-124606D02*
X412739Y-124206D01*
X413139D01*
X412739Y-123805D01*
X413139Y-123406D01*
X412739D01*
X412339Y-123005D01*
X411939Y-123406D01*
X411539D01*
X411939Y-123805D01*
X411539Y-124206D01*
X411939D01*
X412339Y-124606D01*
Y-124206D02*
X412539Y-124005D01*
X412739D01*
X412539Y-123805D01*
X412739Y-123606D01*
X412539D01*
X412339Y-123406D01*
X412139Y-123606D01*
X411939D01*
X412139Y-123805D01*
X411939Y-124005D01*
X412139D01*
X412339Y-124206D01*
X424213Y-176046D02*
X424613Y-175646D01*
X425013D01*
X424613Y-175246D01*
X425013Y-174846D01*
X424613D01*
X424213Y-174446D01*
X423813Y-174846D01*
X423413D01*
X423813Y-175246D01*
X423413Y-175646D01*
X423813D01*
X424213Y-176046D01*
Y-175646D02*
X424413Y-175446D01*
X424613D01*
X424413Y-175246D01*
X424613Y-175046D01*
X424413D01*
X424213Y-174846D01*
X424013Y-175046D01*
X423813D01*
X424013Y-175246D01*
X423813Y-175446D01*
X424013D01*
X424213Y-175646D01*
X314961Y-119746D02*
X315361Y-119346D01*
X315761D01*
X315361Y-118947D01*
X315761Y-118546D01*
X315361D01*
X314961Y-118147D01*
X314561Y-118546D01*
X314161D01*
X314561Y-118947D01*
X314161Y-119346D01*
X314561D01*
X314961Y-119746D01*
Y-119346D02*
X315161Y-119147D01*
X315361D01*
X315161Y-118947D01*
X315361Y-118746D01*
X315161D01*
X314961Y-118546D01*
X314761Y-118746D01*
X314561D01*
X314761Y-118947D01*
X314561Y-119147D01*
X314761D01*
X314961Y-119346D01*
X430807Y-176144D02*
X431207Y-175744D01*
X431607D01*
X431207Y-175344D01*
X431607Y-174944D01*
X431207D01*
X430807Y-174544D01*
X430407Y-174944D01*
X430007D01*
X430407Y-175344D01*
X430007Y-175744D01*
X430407D01*
X430807Y-176144D01*
Y-175744D02*
X431007Y-175544D01*
X431207D01*
X431007Y-175344D01*
X431207Y-175144D01*
X431007D01*
X430807Y-174944D01*
X430607Y-175144D01*
X430407D01*
X430607Y-175344D01*
X430407Y-175544D01*
X430607D01*
X430807Y-175744D01*
X309016Y-129459D02*
X309416Y-129059D01*
X309816D01*
X309416Y-128659D01*
X309816Y-128259D01*
X309416D01*
X309016Y-127859D01*
X308616Y-128259D01*
X308216D01*
X308616Y-128659D01*
X308216Y-129059D01*
X308616D01*
X309016Y-129459D01*
Y-129059D02*
X309216Y-128859D01*
X309416D01*
X309216Y-128659D01*
X309416Y-128459D01*
X309216D01*
X309016Y-128259D01*
X308816Y-128459D01*
X308616D01*
X308816Y-128659D01*
X308616Y-128859D01*
X308816D01*
X309016Y-129059D01*
X418898Y-144943D02*
X419298Y-144543D01*
X419698D01*
X419298Y-144143D01*
X419698Y-143743D01*
X419298D01*
X418898Y-143343D01*
X418498Y-143743D01*
X418098D01*
X418498Y-144143D01*
X418098Y-144543D01*
X418498D01*
X418898Y-144943D01*
Y-144543D02*
X419098Y-144343D01*
X419298D01*
X419098Y-144143D01*
X419298Y-143943D01*
X419098D01*
X418898Y-143743D01*
X418698Y-143943D01*
X418498D01*
X418698Y-144143D01*
X418498Y-144343D01*
X418698D01*
X418898Y-144543D01*
X405512Y-137411D02*
X405912Y-137011D01*
X406312D01*
X405912Y-136611D01*
X406312Y-136211D01*
X405912D01*
X405512Y-135811D01*
X405112Y-136211D01*
X404712D01*
X405112Y-136611D01*
X404712Y-137011D01*
X405112D01*
X405512Y-137411D01*
Y-137011D02*
X405712Y-136811D01*
X405912D01*
X405712Y-136611D01*
X405912Y-136411D01*
X405712D01*
X405512Y-136211D01*
X405312Y-136411D01*
X405112D01*
X405312Y-136611D01*
X405112Y-136811D01*
X405312D01*
X405512Y-137011D01*
X416106Y-144980D02*
X416505Y-144580D01*
X416905D01*
X416505Y-144180D01*
X416905Y-143780D01*
X416505D01*
X416106Y-143380D01*
X415705Y-143780D01*
X415306D01*
X415705Y-144180D01*
X415306Y-144580D01*
X415705D01*
X416106Y-144980D01*
Y-144580D02*
X416305Y-144380D01*
X416505D01*
X416305Y-144180D01*
X416505Y-143980D01*
X416305D01*
X416106Y-143780D01*
X415906Y-143980D01*
X415705D01*
X415906Y-144180D01*
X415705Y-144380D01*
X415906D01*
X416106Y-144580D01*
X398568Y-145883D02*
X398968Y-145483D01*
X399368D01*
X398968Y-145083D01*
X399368Y-144683D01*
X398968D01*
X398568Y-144283D01*
X398168Y-144683D01*
X397768D01*
X398168Y-145083D01*
X397768Y-145483D01*
X398168D01*
X398568Y-145883D01*
Y-145483D02*
X398768Y-145283D01*
X398968D01*
X398768Y-145083D01*
X398968Y-144883D01*
X398768D01*
X398568Y-144683D01*
X398368Y-144883D01*
X398168D01*
X398368Y-145083D01*
X398168Y-145283D01*
X398368D01*
X398568Y-145483D01*
X210433Y-375455D02*
X210833Y-375055D01*
X211233D01*
X210833Y-374655D01*
X211233Y-374255D01*
X210833D01*
X210433Y-373855D01*
X210033Y-374255D01*
X209633D01*
X210033Y-374655D01*
X209633Y-375055D01*
X210033D01*
X210433Y-375455D01*
Y-375055D02*
X210633Y-374855D01*
X210833D01*
X210633Y-374655D01*
X210833Y-374455D01*
X210633D01*
X210433Y-374255D01*
X210233Y-374455D01*
X210033D01*
X210233Y-374655D01*
X210033Y-374855D01*
X210233D01*
X210433Y-375055D01*
X206496Y-375455D02*
X206896Y-375055D01*
X207296D01*
X206896Y-374655D01*
X207296Y-374255D01*
X206896D01*
X206496Y-373855D01*
X206096Y-374255D01*
X205696D01*
X206096Y-374655D01*
X205696Y-375055D01*
X206096D01*
X206496Y-375455D01*
Y-375055D02*
X206696Y-374855D01*
X206896D01*
X206696Y-374655D01*
X206896Y-374455D01*
X206696D01*
X206496Y-374255D01*
X206296Y-374455D01*
X206096D01*
X206296Y-374655D01*
X206096Y-374855D01*
X206296D01*
X206496Y-375055D01*
X442126Y-307542D02*
X442526Y-307142D01*
X442926D01*
X442526Y-306742D01*
X442926Y-306342D01*
X442526D01*
X442126Y-305942D01*
X441726Y-306342D01*
X441326D01*
X441726Y-306742D01*
X441326Y-307142D01*
X441726D01*
X442126Y-307542D01*
Y-307142D02*
X442326Y-306942D01*
X442526D01*
X442326Y-306742D01*
X442526Y-306542D01*
X442326D01*
X442126Y-306342D01*
X441926Y-306542D01*
X441726D01*
X441926Y-306742D01*
X441726Y-306942D01*
X441926D01*
X442126Y-307142D01*
X439370Y-307542D02*
X439770Y-307142D01*
X440170D01*
X439770Y-306742D01*
X440170Y-306342D01*
X439770D01*
X439370Y-305942D01*
X438970Y-306342D01*
X438570D01*
X438970Y-306742D01*
X438570Y-307142D01*
X438970D01*
X439370Y-307542D01*
Y-307142D02*
X439570Y-306942D01*
X439770D01*
X439570Y-306742D01*
X439770Y-306542D01*
X439570D01*
X439370Y-306342D01*
X439170Y-306542D01*
X438970D01*
X439170Y-306742D01*
X438970Y-306942D01*
X439170D01*
X439370Y-307142D01*
X237992Y-375455D02*
X238392Y-375055D01*
X238792D01*
X238392Y-374655D01*
X238792Y-374255D01*
X238392D01*
X237992Y-373855D01*
X237592Y-374255D01*
X237192D01*
X237592Y-374655D01*
X237192Y-375055D01*
X237592D01*
X237992Y-375455D01*
Y-375055D02*
X238192Y-374855D01*
X238392D01*
X238192Y-374655D01*
X238392Y-374455D01*
X238192D01*
X237992Y-374255D01*
X237792Y-374455D01*
X237592D01*
X237792Y-374655D01*
X237592Y-374855D01*
X237792D01*
X237992Y-375055D01*
X241929Y-375455D02*
X242329Y-375055D01*
X242729D01*
X242329Y-374655D01*
X242729Y-374255D01*
X242329D01*
X241929Y-373855D01*
X241529Y-374255D01*
X241129D01*
X241529Y-374655D01*
X241129Y-375055D01*
X241529D01*
X241929Y-375455D01*
Y-375055D02*
X242129Y-374855D01*
X242329D01*
X242129Y-374655D01*
X242329Y-374455D01*
X242129D01*
X241929Y-374255D01*
X241729Y-374455D01*
X241529D01*
X241729Y-374655D01*
X241529Y-374855D01*
X241729D01*
X241929Y-375055D01*
X253655Y-375221D02*
X254055Y-374821D01*
X254455D01*
X254055Y-374421D01*
X254455Y-374021D01*
X254055D01*
X253655Y-373621D01*
X253255Y-374021D01*
X252855D01*
X253255Y-374421D01*
X252855Y-374821D01*
X253255D01*
X253655Y-375221D01*
Y-374821D02*
X253855Y-374621D01*
X254055D01*
X253855Y-374421D01*
X254055Y-374221D01*
X253855D01*
X253655Y-374021D01*
X253455Y-374221D01*
X253255D01*
X253455Y-374421D01*
X253255Y-374621D01*
X253455D01*
X253655Y-374821D01*
X256890Y-375455D02*
X257290Y-375055D01*
X257690D01*
X257290Y-374655D01*
X257690Y-374255D01*
X257290D01*
X256890Y-373855D01*
X256490Y-374255D01*
X256090D01*
X256490Y-374655D01*
X256090Y-375055D01*
X256490D01*
X256890Y-375455D01*
Y-375055D02*
X257090Y-374855D01*
X257290D01*
X257090Y-374655D01*
X257290Y-374455D01*
X257090D01*
X256890Y-374255D01*
X256690Y-374455D01*
X256490D01*
X256690Y-374655D01*
X256490Y-374855D01*
X256690D01*
X256890Y-375055D01*
X273425Y-375455D02*
X273825Y-375055D01*
X274225D01*
X273825Y-374655D01*
X274225Y-374255D01*
X273825D01*
X273425Y-373855D01*
X273025Y-374255D01*
X272625D01*
X273025Y-374655D01*
X272625Y-375055D01*
X273025D01*
X273425Y-375455D01*
Y-375055D02*
X273625Y-374855D01*
X273825D01*
X273625Y-374655D01*
X273825Y-374455D01*
X273625D01*
X273425Y-374255D01*
X273225Y-374455D01*
X273025D01*
X273225Y-374655D01*
X273025Y-374855D01*
X273225D01*
X273425Y-375055D01*
X269502Y-375091D02*
X269902Y-374691D01*
X270302D01*
X269902Y-374291D01*
X270302Y-373891D01*
X269902D01*
X269502Y-373491D01*
X269102Y-373891D01*
X268702D01*
X269102Y-374291D01*
X268702Y-374691D01*
X269102D01*
X269502Y-375091D01*
Y-374691D02*
X269702Y-374491D01*
X269902D01*
X269702Y-374291D01*
X269902Y-374091D01*
X269702D01*
X269502Y-373891D01*
X269302Y-374091D01*
X269102D01*
X269302Y-374291D01*
X269102Y-374491D01*
X269302D01*
X269502Y-374691D01*
X246339Y-387775D02*
X246739Y-387375D01*
X247139D01*
X246739Y-386975D01*
X247139Y-386575D01*
X246739D01*
X246339Y-386175D01*
X245939Y-386575D01*
X245539D01*
X245939Y-386975D01*
X245539Y-387375D01*
X245939D01*
X246339Y-387775D01*
Y-387375D02*
X246539Y-387175D01*
X246739D01*
X246539Y-386975D01*
X246739Y-386775D01*
X246539D01*
X246339Y-386575D01*
X246139Y-386775D01*
X245939D01*
X246139Y-386975D01*
X245939Y-387175D01*
X246139D01*
X246339Y-387375D01*
X249410Y-388053D02*
X249810Y-387653D01*
X250209D01*
X249810Y-387253D01*
X250209Y-386854D01*
X249810D01*
X249410Y-386454D01*
X249009Y-386854D01*
X248609D01*
X249009Y-387253D01*
X248609Y-387653D01*
X249009D01*
X249410Y-388053D01*
Y-387653D02*
X249609Y-387454D01*
X249810D01*
X249609Y-387253D01*
X249810Y-387053D01*
X249609D01*
X249410Y-386854D01*
X249209Y-387053D01*
X249009D01*
X249209Y-387253D01*
X249009Y-387454D01*
X249209D01*
X249410Y-387653D01*
X232480Y-388053D02*
X232880Y-387653D01*
X233280D01*
X232880Y-387253D01*
X233280Y-386854D01*
X232880D01*
X232480Y-386454D01*
X232080Y-386854D01*
X231680D01*
X232080Y-387253D01*
X231680Y-387653D01*
X232080D01*
X232480Y-388053D01*
Y-387653D02*
X232680Y-387454D01*
X232880D01*
X232680Y-387253D01*
X232880Y-387053D01*
X232680D01*
X232480Y-386854D01*
X232280Y-387053D01*
X232080D01*
X232280Y-387253D01*
X232080Y-387454D01*
X232280D01*
X232480Y-387653D01*
X229331Y-388053D02*
X229731Y-387653D01*
X230131D01*
X229731Y-387253D01*
X230131Y-386854D01*
X229731D01*
X229331Y-386454D01*
X228931Y-386854D01*
X228531D01*
X228931Y-387253D01*
X228531Y-387653D01*
X228931D01*
X229331Y-388053D01*
Y-387653D02*
X229531Y-387454D01*
X229731D01*
X229531Y-387253D01*
X229731Y-387053D01*
X229531D01*
X229331Y-386854D01*
X229131Y-387053D01*
X228931D01*
X229131Y-387253D01*
X228931Y-387454D01*
X229131D01*
X229331Y-387653D01*
X436221Y-307542D02*
X436621Y-307142D01*
X437020D01*
X436621Y-306742D01*
X437020Y-306342D01*
X436621D01*
X436221Y-305942D01*
X435820Y-306342D01*
X435421D01*
X435820Y-306742D01*
X435421Y-307142D01*
X435820D01*
X436221Y-307542D01*
Y-307142D02*
X436420Y-306942D01*
X436621D01*
X436420Y-306742D01*
X436621Y-306542D01*
X436420D01*
X436221Y-306342D01*
X436021Y-306542D01*
X435820D01*
X436021Y-306742D01*
X435820Y-306942D01*
X436021D01*
X436221Y-307142D01*
X212795Y-388053D02*
X213195Y-387653D01*
X213595D01*
X213195Y-387253D01*
X213595Y-386854D01*
X213195D01*
X212795Y-386454D01*
X212395Y-386854D01*
X211995D01*
X212395Y-387253D01*
X211995Y-387653D01*
X212395D01*
X212795Y-388053D01*
Y-387653D02*
X212995Y-387454D01*
X213195D01*
X212995Y-387253D01*
X213195Y-387053D01*
X212995D01*
X212795Y-386854D01*
X212595Y-387053D01*
X212395D01*
X212595Y-387253D01*
X212395Y-387454D01*
X212595D01*
X212795Y-387653D01*
X433465Y-307542D02*
X433865Y-307142D01*
X434265D01*
X433865Y-306742D01*
X434265Y-306342D01*
X433865D01*
X433465Y-305942D01*
X433065Y-306342D01*
X432665D01*
X433065Y-306742D01*
X432665Y-307142D01*
X433065D01*
X433465Y-307542D01*
Y-307142D02*
X433665Y-306942D01*
X433865D01*
X433665Y-306742D01*
X433865Y-306542D01*
X433665D01*
X433465Y-306342D01*
X433265Y-306542D01*
X433065D01*
X433265Y-306742D01*
X433065Y-306942D01*
X433265D01*
X433465Y-307142D01*
X215945Y-388053D02*
X216345Y-387653D01*
X216745D01*
X216345Y-387253D01*
X216745Y-386854D01*
X216345D01*
X215945Y-386454D01*
X215545Y-386854D01*
X215145D01*
X215545Y-387253D01*
X215145Y-387653D01*
X215545D01*
X215945Y-388053D01*
Y-387653D02*
X216145Y-387454D01*
X216345D01*
X216145Y-387253D01*
X216345Y-387053D01*
X216145D01*
X215945Y-386854D01*
X215745Y-387053D01*
X215545D01*
X215745Y-387253D01*
X215545Y-387454D01*
X215745D01*
X215945Y-387653D01*
X262006Y-388055D02*
X262406Y-387655D01*
X262806D01*
X262406Y-387255D01*
X262806Y-386855D01*
X262406D01*
X262006Y-386455D01*
X261606Y-386855D01*
X261206D01*
X261606Y-387255D01*
X261206Y-387655D01*
X261606D01*
X262006Y-388055D01*
Y-387655D02*
X262206Y-387455D01*
X262406D01*
X262206Y-387255D01*
X262406Y-387055D01*
X262206D01*
X262006Y-386855D01*
X261806Y-387055D01*
X261606D01*
X261806Y-387255D01*
X261606Y-387455D01*
X261806D01*
X262006Y-387655D01*
X448032Y-307542D02*
X448431Y-307142D01*
X448832D01*
X448431Y-306742D01*
X448832Y-306342D01*
X448431D01*
X448032Y-305942D01*
X447632Y-306342D01*
X447231D01*
X447632Y-306742D01*
X447231Y-307142D01*
X447632D01*
X448032Y-307542D01*
Y-307142D02*
X448232Y-306942D01*
X448431D01*
X448232Y-306742D01*
X448431Y-306542D01*
X448232D01*
X448032Y-306342D01*
X447831Y-306542D01*
X447632D01*
X447831Y-306742D01*
X447632Y-306942D01*
X447831D01*
X448032Y-307142D01*
X265158Y-388053D02*
X265558Y-387653D01*
X265957D01*
X265558Y-387253D01*
X265957Y-386854D01*
X265558D01*
X265158Y-386454D01*
X264757Y-386854D01*
X264357D01*
X264757Y-387253D01*
X264357Y-387653D01*
X264757D01*
X265158Y-388053D01*
Y-387653D02*
X265357Y-387454D01*
X265558D01*
X265357Y-387253D01*
X265558Y-387053D01*
X265357D01*
X265158Y-386854D01*
X264957Y-387053D01*
X264757D01*
X264957Y-387253D01*
X264757Y-387454D01*
X264957D01*
X265158Y-387653D01*
X445276Y-307542D02*
X445676Y-307142D01*
X446076D01*
X445676Y-306742D01*
X446076Y-306342D01*
X445676D01*
X445276Y-305942D01*
X444876Y-306342D01*
X444476D01*
X444876Y-306742D01*
X444476Y-307142D01*
X444876D01*
X445276Y-307542D01*
Y-307142D02*
X445476Y-306942D01*
X445676D01*
X445476Y-306742D01*
X445676Y-306542D01*
X445476D01*
X445276Y-306342D01*
X445076Y-306542D01*
X444876D01*
X445076Y-306742D01*
X444876Y-306942D01*
X445076D01*
X445276Y-307142D01*
X104528Y-92975D02*
X104928Y-92575D01*
X105328D01*
X104928Y-92175D01*
X105328Y-91775D01*
X104928D01*
X104528Y-91375D01*
X104128Y-91775D01*
X103728D01*
X104128Y-92175D01*
X103728Y-92575D01*
X104128D01*
X104528Y-92975D01*
Y-92575D02*
X104728Y-92375D01*
X104928D01*
X104728Y-92175D01*
X104928Y-91975D01*
X104728D01*
X104528Y-91775D01*
X104328Y-91975D01*
X104128D01*
X104328Y-92175D01*
X104128Y-92375D01*
X104328D01*
X104528Y-92575D01*
X269685Y-106951D02*
X270085Y-106551D01*
X270485D01*
X270085Y-106151D01*
X270485Y-105751D01*
X270085D01*
X269685Y-105351D01*
X269285Y-105751D01*
X268885D01*
X269285Y-106151D01*
X268885Y-106551D01*
X269285D01*
X269685Y-106951D01*
Y-106551D02*
X269885Y-106351D01*
X270085D01*
X269885Y-106151D01*
X270085Y-105951D01*
X269885D01*
X269685Y-105751D01*
X269485Y-105951D01*
X269285D01*
X269485Y-106151D01*
X269285Y-106351D01*
X269485D01*
X269685Y-106551D01*
X244094Y-109904D02*
X244495Y-109504D01*
X244895D01*
X244495Y-109104D01*
X244895Y-108704D01*
X244495D01*
X244094Y-108304D01*
X243694Y-108704D01*
X243295D01*
X243694Y-109104D01*
X243295Y-109504D01*
X243694D01*
X244094Y-109904D01*
Y-109504D02*
X244295Y-109304D01*
X244495D01*
X244295Y-109104D01*
X244495Y-108904D01*
X244295D01*
X244094Y-108704D01*
X243895Y-108904D01*
X243694D01*
X243895Y-109104D01*
X243694Y-109304D01*
X243895D01*
X244094Y-109504D01*
X475295Y-134412D02*
X475695Y-134012D01*
X476095D01*
X475695Y-133612D01*
X476095Y-133212D01*
X475695D01*
X475295Y-132812D01*
X474895Y-133212D01*
X474495D01*
X474895Y-133612D01*
X474495Y-134012D01*
X474895D01*
X475295Y-134412D01*
Y-134012D02*
X475495Y-133812D01*
X475695D01*
X475495Y-133612D01*
X475695Y-133412D01*
X475495D01*
X475295Y-133212D01*
X475095Y-133412D01*
X474895D01*
X475095Y-133612D01*
X474895Y-133812D01*
X475095D01*
X475295Y-134012D01*
X505905Y-132542D02*
X506306Y-132142D01*
X506706D01*
X506306Y-131742D01*
X506706Y-131342D01*
X506306D01*
X505905Y-130942D01*
X505506Y-131342D01*
X505105D01*
X505506Y-131742D01*
X505105Y-132142D01*
X505506D01*
X505905Y-132542D01*
Y-132142D02*
X506106Y-131942D01*
X506306D01*
X506106Y-131742D01*
X506306Y-131542D01*
X506106D01*
X505905Y-131342D01*
X505705Y-131542D01*
X505506D01*
X505705Y-131742D01*
X505506Y-131942D01*
X505705D01*
X505905Y-132142D01*
X131890Y-73487D02*
X132290Y-73087D01*
X132690D01*
X132290Y-72687D01*
X132690Y-72287D01*
X132290D01*
X131890Y-71887D01*
X131490Y-72287D01*
X131090D01*
X131490Y-72687D01*
X131090Y-73087D01*
X131490D01*
X131890Y-73487D01*
Y-73087D02*
X132090Y-72887D01*
X132290D01*
X132090Y-72687D01*
X132290Y-72487D01*
X132090D01*
X131890Y-72287D01*
X131690Y-72487D01*
X131490D01*
X131690Y-72687D01*
X131490Y-72887D01*
X131690D01*
X131890Y-73087D01*
X179134Y-387266D02*
X179534Y-386866D01*
X179934D01*
X179534Y-386466D01*
X179934Y-386066D01*
X179534D01*
X179134Y-385666D01*
X178734Y-386066D01*
X178334D01*
X178734Y-386466D01*
X178334Y-386866D01*
X178734D01*
X179134Y-387266D01*
Y-386866D02*
X179334Y-386666D01*
X179534D01*
X179334Y-386466D01*
X179534Y-386266D01*
X179334D01*
X179134Y-386066D01*
X178934Y-386266D01*
X178734D01*
X178934Y-386466D01*
X178734Y-386666D01*
X178934D01*
X179134Y-386866D01*
Y-390416D02*
X179534Y-390016D01*
X179934D01*
X179534Y-389616D01*
X179934Y-389216D01*
X179534D01*
X179134Y-388816D01*
X178734Y-389216D01*
X178334D01*
X178734Y-389616D01*
X178334Y-390016D01*
X178734D01*
X179134Y-390416D01*
Y-390016D02*
X179334Y-389816D01*
X179534D01*
X179334Y-389616D01*
X179534Y-389416D01*
X179334D01*
X179134Y-389216D01*
X178934Y-389416D01*
X178734D01*
X178934Y-389616D01*
X178734Y-389816D01*
X178934D01*
X179134Y-390016D01*
X178543Y-378211D02*
X178943Y-377811D01*
X179343D01*
X178943Y-377411D01*
X179343Y-377011D01*
X178943D01*
X178543Y-376611D01*
X178143Y-377011D01*
X177743D01*
X178143Y-377411D01*
X177743Y-377811D01*
X178143D01*
X178543Y-378211D01*
Y-377811D02*
X178743Y-377611D01*
X178943D01*
X178743Y-377411D01*
X178943Y-377211D01*
X178743D01*
X178543Y-377011D01*
X178343Y-377211D01*
X178143D01*
X178343Y-377411D01*
X178143Y-377611D01*
X178343D01*
X178543Y-377811D01*
X534400Y-127769D02*
X534800Y-127368D01*
X535200D01*
X534800Y-126969D01*
X535200Y-126568D01*
X534800D01*
X534400Y-126169D01*
X534000Y-126568D01*
X533600D01*
X534000Y-126969D01*
X533600Y-127368D01*
X534000D01*
X534400Y-127769D01*
Y-127368D02*
X534600Y-127169D01*
X534800D01*
X534600Y-126969D01*
X534800Y-126769D01*
X534600D01*
X534400Y-126568D01*
X534200Y-126769D01*
X534000D01*
X534200Y-126969D01*
X534000Y-127169D01*
X534200D01*
X534400Y-127368D01*
X443898Y-175849D02*
X444298Y-175449D01*
X444698D01*
X444298Y-175049D01*
X444698Y-174649D01*
X444298D01*
X443898Y-174249D01*
X443498Y-174649D01*
X443098D01*
X443498Y-175049D01*
X443098Y-175449D01*
X443498D01*
X443898Y-175849D01*
Y-175449D02*
X444098Y-175249D01*
X444298D01*
X444098Y-175049D01*
X444298Y-174849D01*
X444098D01*
X443898Y-174649D01*
X443698Y-174849D01*
X443498D01*
X443698Y-175049D01*
X443498Y-175249D01*
X443698D01*
X443898Y-175449D01*
X99410Y-66597D02*
X99809Y-66197D01*
X100209D01*
X99809Y-65797D01*
X100209Y-65397D01*
X99809D01*
X99410Y-64997D01*
X99010Y-65397D01*
X98610D01*
X99010Y-65797D01*
X98610Y-66197D01*
X99010D01*
X99410Y-66597D01*
Y-66197D02*
X99610Y-65997D01*
X99809D01*
X99610Y-65797D01*
X99809Y-65597D01*
X99610D01*
X99410Y-65397D01*
X99209Y-65597D01*
X99010D01*
X99209Y-65797D01*
X99010Y-65997D01*
X99209D01*
X99410Y-66197D01*
Y-58723D02*
X99809Y-58323D01*
X100209D01*
X99809Y-57923D01*
X100209Y-57523D01*
X99809D01*
X99410Y-57123D01*
X99010Y-57523D01*
X98610D01*
X99010Y-57923D01*
X98610Y-58323D01*
X99010D01*
X99410Y-58723D01*
Y-58323D02*
X99610Y-58123D01*
X99809D01*
X99610Y-57923D01*
X99809Y-57723D01*
X99610D01*
X99410Y-57523D01*
X99209Y-57723D01*
X99010D01*
X99209Y-57923D01*
X99010Y-58123D01*
X99209D01*
X99410Y-58323D01*
X65945Y-66597D02*
X66345Y-66197D01*
X66745D01*
X66345Y-65797D01*
X66745Y-65397D01*
X66345D01*
X65945Y-64997D01*
X65545Y-65397D01*
X65145D01*
X65545Y-65797D01*
X65145Y-66197D01*
X65545D01*
X65945Y-66597D01*
Y-66197D02*
X66145Y-65997D01*
X66345D01*
X66145Y-65797D01*
X66345Y-65597D01*
X66145D01*
X65945Y-65397D01*
X65745Y-65597D01*
X65545D01*
X65745Y-65797D01*
X65545Y-65997D01*
X65745D01*
X65945Y-66197D01*
Y-50849D02*
X66345Y-50449D01*
X66745D01*
X66345Y-50049D01*
X66745Y-49649D01*
X66345D01*
X65945Y-49249D01*
X65545Y-49649D01*
X65145D01*
X65545Y-50049D01*
X65145Y-50449D01*
X65545D01*
X65945Y-50849D01*
Y-50449D02*
X66145Y-50249D01*
X66345D01*
X66145Y-50049D01*
X66345Y-49849D01*
X66145D01*
X65945Y-49649D01*
X65745Y-49849D01*
X65545D01*
X65745Y-50049D01*
X65545Y-50249D01*
X65745D01*
X65945Y-50449D01*
X78740Y-238841D02*
X79140Y-238441D01*
X79540D01*
X79140Y-238041D01*
X79540Y-237641D01*
X79140D01*
X78740Y-237241D01*
X78340Y-237641D01*
X77940D01*
X78340Y-238041D01*
X77940Y-238441D01*
X78340D01*
X78740Y-238841D01*
Y-238441D02*
X78940Y-238241D01*
X79140D01*
X78940Y-238041D01*
X79140Y-237841D01*
X78940D01*
X78740Y-237641D01*
X78540Y-237841D01*
X78340D01*
X78540Y-238041D01*
X78340Y-238241D01*
X78540D01*
X78740Y-238441D01*
X33465Y19033D02*
X33865Y19433D01*
X34265D01*
X33865Y19833D01*
X34265Y20233D01*
X33865D01*
X33465Y20633D01*
X33065Y20233D01*
X32665D01*
X33065Y19833D01*
X32665Y19433D01*
X33065D01*
X33465Y19033D01*
Y19433D02*
X33665Y19633D01*
X33865D01*
X33665Y19833D01*
X33865Y20033D01*
X33665D01*
X33465Y20233D01*
X33265Y20033D01*
X33065D01*
X33265Y19833D01*
X33065Y19633D01*
X33265D01*
X33465Y19433D01*
X40354Y18885D02*
X40754Y19285D01*
X41154D01*
X40754Y19685D01*
X41154Y20085D01*
X40754D01*
X40354Y20485D01*
X39954Y20085D01*
X39554D01*
X39954Y19685D01*
X39554Y19285D01*
X39954D01*
X40354Y18885D01*
Y19285D02*
X40554Y19485D01*
X40754D01*
X40554Y19685D01*
X40754Y19885D01*
X40554D01*
X40354Y20085D01*
X40154Y19885D01*
X39954D01*
X40154Y19685D01*
X39954Y19485D01*
X40154D01*
X40354Y19285D01*
X47244Y18885D02*
X47644Y19285D01*
X48044D01*
X47644Y19685D01*
X48044Y20085D01*
X47644D01*
X47244Y20485D01*
X46844Y20085D01*
X46444D01*
X46844Y19685D01*
X46444Y19285D01*
X46844D01*
X47244Y18885D01*
Y19285D02*
X47444Y19485D01*
X47644D01*
X47444Y19685D01*
X47644Y19885D01*
X47444D01*
X47244Y20085D01*
X47044Y19885D01*
X46844D01*
X47044Y19685D01*
X46844Y19485D01*
X47044D01*
X47244Y19285D01*
X483268Y-114825D02*
X483668Y-114425D01*
X484068D01*
X483668Y-114025D01*
X484068Y-113625D01*
X483668D01*
X483268Y-113225D01*
X482868Y-113625D01*
X482468D01*
X482868Y-114025D01*
X482468Y-114425D01*
X482868D01*
X483268Y-114825D01*
Y-114425D02*
X483468Y-114225D01*
X483668D01*
X483468Y-114025D01*
X483668Y-113825D01*
X483468D01*
X483268Y-113625D01*
X483068Y-113825D01*
X482868D01*
X483068Y-114025D01*
X482868Y-114225D01*
X483068D01*
X483268Y-114425D01*
X492319Y-115770D02*
X492720Y-115370D01*
X493119D01*
X492720Y-114970D01*
X493119Y-114570D01*
X492720D01*
X492319Y-114170D01*
X491920Y-114570D01*
X491519D01*
X491920Y-114970D01*
X491519Y-115370D01*
X491920D01*
X492319Y-115770D01*
Y-115370D02*
X492520Y-115170D01*
X492720D01*
X492520Y-114970D01*
X492720Y-114770D01*
X492520D01*
X492319Y-114570D01*
X492120Y-114770D01*
X491920D01*
X492120Y-114970D01*
X491920Y-115170D01*
X492120D01*
X492319Y-115370D01*
X487205Y-114857D02*
X487605Y-114457D01*
X488005D01*
X487605Y-114057D01*
X488005Y-113657D01*
X487605D01*
X487205Y-113257D01*
X486805Y-113657D01*
X486405D01*
X486805Y-114057D01*
X486405Y-114457D01*
X486805D01*
X487205Y-114857D01*
Y-114457D02*
X487405Y-114257D01*
X487605D01*
X487405Y-114057D01*
X487605Y-113857D01*
X487405D01*
X487205Y-113657D01*
X487005Y-113857D01*
X486805D01*
X487005Y-114057D01*
X486805Y-114257D01*
X487005D01*
X487205Y-114457D01*
X456742Y-116843D02*
X457142Y-116443D01*
X457542D01*
X457142Y-116043D01*
X457542Y-115643D01*
X457142D01*
X456742Y-115243D01*
X456342Y-115643D01*
X455942D01*
X456342Y-116043D01*
X455942Y-116443D01*
X456342D01*
X456742Y-116843D01*
Y-116443D02*
X456942Y-116243D01*
X457142D01*
X456942Y-116043D01*
X457142Y-115843D01*
X456942D01*
X456742Y-115643D01*
X456542Y-115843D01*
X456342D01*
X456542Y-116043D01*
X456342Y-116243D01*
X456542D01*
X456742Y-116443D01*
X464328Y-147197D02*
X464728Y-146797D01*
X465128D01*
X464728Y-146397D01*
X465128Y-145997D01*
X464728D01*
X464328Y-145597D01*
X463928Y-145997D01*
X463528D01*
X463928Y-146397D01*
X463528Y-146797D01*
X463928D01*
X464328Y-147197D01*
Y-146797D02*
X464528Y-146597D01*
X464728D01*
X464528Y-146397D01*
X464728Y-146197D01*
X464528D01*
X464328Y-145997D01*
X464128Y-146197D01*
X463928D01*
X464128Y-146397D01*
X463928Y-146597D01*
X464128D01*
X464328Y-146797D01*
X469291Y-144648D02*
X469691Y-144248D01*
X470091D01*
X469691Y-143848D01*
X470091Y-143448D01*
X469691D01*
X469291Y-143048D01*
X468891Y-143448D01*
X468491D01*
X468891Y-143848D01*
X468491Y-144248D01*
X468891D01*
X469291Y-144648D01*
Y-144248D02*
X469491Y-144048D01*
X469691D01*
X469491Y-143848D01*
X469691Y-143648D01*
X469491D01*
X469291Y-143448D01*
X469091Y-143648D01*
X468891D01*
X469091Y-143848D01*
X468891Y-144048D01*
X469091D01*
X469291Y-144248D01*
X461319Y-144550D02*
X461719Y-144150D01*
X462119D01*
X461719Y-143750D01*
X462119Y-143350D01*
X461719D01*
X461319Y-142950D01*
X460919Y-143350D01*
X460519D01*
X460919Y-143750D01*
X460519Y-144150D01*
X460919D01*
X461319Y-144550D01*
Y-144150D02*
X461519Y-143950D01*
X461719D01*
X461519Y-143750D01*
X461719Y-143550D01*
X461519D01*
X461319Y-143350D01*
X461119Y-143550D01*
X460919D01*
X461119Y-143750D01*
X460919Y-143950D01*
X461119D01*
X461319Y-144150D01*
X267323Y-123684D02*
X267723Y-123284D01*
X268123D01*
X267723Y-122883D01*
X268123Y-122484D01*
X267723D01*
X267323Y-122083D01*
X266923Y-122484D01*
X266523D01*
X266923Y-122883D01*
X266523Y-123284D01*
X266923D01*
X267323Y-123684D01*
Y-123284D02*
X267523Y-123083D01*
X267723D01*
X267523Y-122883D01*
X267723Y-122684D01*
X267523D01*
X267323Y-122484D01*
X267123Y-122684D01*
X266923D01*
X267123Y-122883D01*
X266923Y-123083D01*
X267123D01*
X267323Y-123284D01*
X457283Y-175947D02*
X457684Y-175547D01*
X458083D01*
X457684Y-175147D01*
X458083Y-174747D01*
X457684D01*
X457283Y-174347D01*
X456883Y-174747D01*
X456484D01*
X456883Y-175147D01*
X456484Y-175547D01*
X456883D01*
X457283Y-175947D01*
Y-175547D02*
X457483Y-175347D01*
X457684D01*
X457483Y-175147D01*
X457684Y-174947D01*
X457483D01*
X457283Y-174747D01*
X457084Y-174947D01*
X456883D01*
X457084Y-175147D01*
X456883Y-175347D01*
X457084D01*
X457283Y-175547D01*
X469390Y-175947D02*
X469790Y-175547D01*
X470190D01*
X469790Y-175147D01*
X470190Y-174747D01*
X469790D01*
X469390Y-174347D01*
X468990Y-174747D01*
X468590D01*
X468990Y-175147D01*
X468590Y-175547D01*
X468990D01*
X469390Y-175947D01*
Y-175547D02*
X469590Y-175347D01*
X469790D01*
X469590Y-175147D01*
X469790Y-174947D01*
X469590D01*
X469390Y-174747D01*
X469190Y-174947D01*
X468990D01*
X469190Y-175147D01*
X468990Y-175347D01*
X469190D01*
X469390Y-175547D01*
X544291Y-216203D02*
X544691Y-215803D01*
X545091D01*
X544691Y-215403D01*
X545091Y-215003D01*
X544691D01*
X544291Y-214603D01*
X543891Y-215003D01*
X543491D01*
X543891Y-215403D01*
X543491Y-215803D01*
X543891D01*
X544291Y-216203D01*
Y-215803D02*
X544491Y-215603D01*
X544691D01*
X544491Y-215403D01*
X544691Y-215203D01*
X544491D01*
X544291Y-215003D01*
X544091Y-215203D01*
X543891D01*
X544091Y-215403D01*
X543891Y-215603D01*
X544091D01*
X544291Y-215803D01*
X512402Y-262758D02*
X512802Y-262358D01*
X513202D01*
X512802Y-261958D01*
X513202Y-261558D01*
X512802D01*
X512402Y-261158D01*
X512002Y-261558D01*
X511602D01*
X512002Y-261958D01*
X511602Y-262358D01*
X512002D01*
X512402Y-262758D01*
Y-262358D02*
X512602Y-262158D01*
X512802D01*
X512602Y-261958D01*
X512802Y-261758D01*
X512602D01*
X512402Y-261558D01*
X512202Y-261758D01*
X512002D01*
X512202Y-261958D01*
X512002Y-262158D01*
X512202D01*
X512402Y-262358D01*
Y-265908D02*
X512802Y-265508D01*
X513202D01*
X512802Y-265108D01*
X513202Y-264708D01*
X512802D01*
X512402Y-264308D01*
X512002Y-264708D01*
X511602D01*
X512002Y-265108D01*
X511602Y-265508D01*
X512002D01*
X512402Y-265908D01*
Y-265508D02*
X512602Y-265308D01*
X512802D01*
X512602Y-265108D01*
X512802Y-264908D01*
X512602D01*
X512402Y-264708D01*
X512202Y-264908D01*
X512002D01*
X512202Y-265108D01*
X512002Y-265308D01*
X512202D01*
X512402Y-265508D01*
X512543Y-268865D02*
X512943Y-268465D01*
X513343D01*
X512943Y-268065D01*
X513343Y-267665D01*
X512943D01*
X512543Y-267265D01*
X512143Y-267665D01*
X511743D01*
X512143Y-268065D01*
X511743Y-268465D01*
X512143D01*
X512543Y-268865D01*
Y-268465D02*
X512743Y-268265D01*
X512943D01*
X512743Y-268065D01*
X512943Y-267865D01*
X512743D01*
X512543Y-267665D01*
X512343Y-267865D01*
X512143D01*
X512343Y-268065D01*
X512143Y-268265D01*
X512343D01*
X512543Y-268465D01*
X437697Y-176046D02*
X438097Y-175646D01*
X438497D01*
X438097Y-175246D01*
X438497Y-174846D01*
X438097D01*
X437697Y-174446D01*
X437297Y-174846D01*
X436897D01*
X437297Y-175246D01*
X436897Y-175646D01*
X437297D01*
X437697Y-176046D01*
Y-175646D02*
X437897Y-175446D01*
X438097D01*
X437897Y-175246D01*
X438097Y-175046D01*
X437897D01*
X437697Y-174846D01*
X437497Y-175046D01*
X437297D01*
X437497Y-175246D01*
X437297Y-175446D01*
X437497D01*
X437697Y-175646D01*
X433858Y-176046D02*
X434258Y-175646D01*
X434658D01*
X434258Y-175246D01*
X434658Y-174846D01*
X434258D01*
X433858Y-174446D01*
X433458Y-174846D01*
X433058D01*
X433458Y-175246D01*
X433058Y-175646D01*
X433458D01*
X433858Y-176046D01*
Y-175646D02*
X434058Y-175446D01*
X434258D01*
X434058Y-175246D01*
X434258Y-175046D01*
X434058D01*
X433858Y-174846D01*
X433658Y-175046D01*
X433458D01*
X433658Y-175246D01*
X433458Y-175446D01*
X433658D01*
X433858Y-175646D01*
X404823Y-176144D02*
X405223Y-175744D01*
X405623D01*
X405223Y-175344D01*
X405623Y-174944D01*
X405223D01*
X404823Y-174544D01*
X404423Y-174944D01*
X404023D01*
X404423Y-175344D01*
X404023Y-175744D01*
X404423D01*
X404823Y-176144D01*
Y-175744D02*
X405023Y-175544D01*
X405223D01*
X405023Y-175344D01*
X405223Y-175144D01*
X405023D01*
X404823Y-174944D01*
X404623Y-175144D01*
X404423D01*
X404623Y-175344D01*
X404423Y-175544D01*
X404623D01*
X404823Y-175744D01*
X402264Y-176144D02*
X402664Y-175744D01*
X403064D01*
X402664Y-175344D01*
X403064Y-174944D01*
X402664D01*
X402264Y-174544D01*
X401864Y-174944D01*
X401464D01*
X401864Y-175344D01*
X401464Y-175744D01*
X401864D01*
X402264Y-176144D01*
Y-175744D02*
X402464Y-175544D01*
X402664D01*
X402464Y-175344D01*
X402664Y-175144D01*
X402464D01*
X402264Y-174944D01*
X402064Y-175144D01*
X401864D01*
X402064Y-175344D01*
X401864Y-175544D01*
X402064D01*
X402264Y-175744D01*
X237008Y-130376D02*
X237408Y-129976D01*
X237808D01*
X237408Y-129576D01*
X237808Y-129176D01*
X237408D01*
X237008Y-128776D01*
X236608Y-129176D01*
X236208D01*
X236608Y-129576D01*
X236208Y-129976D01*
X236608D01*
X237008Y-130376D01*
Y-129976D02*
X237208Y-129776D01*
X237408D01*
X237208Y-129576D01*
X237408Y-129376D01*
X237208D01*
X237008Y-129176D01*
X236808Y-129376D01*
X236608D01*
X236808Y-129576D01*
X236608Y-129776D01*
X236808D01*
X237008Y-129976D01*
X309016Y-114786D02*
X309416Y-114386D01*
X309816D01*
X309416Y-113986D01*
X309816Y-113586D01*
X309416D01*
X309016Y-113186D01*
X308616Y-113586D01*
X308216D01*
X308616Y-113986D01*
X308216Y-114386D01*
X308616D01*
X309016Y-114786D01*
Y-114386D02*
X309216Y-114186D01*
X309416D01*
X309216Y-113986D01*
X309416Y-113786D01*
X309216D01*
X309016Y-113586D01*
X308816Y-113786D01*
X308616D01*
X308816Y-113986D01*
X308616Y-114186D01*
X308816D01*
X309016Y-114386D01*
X193898Y-115809D02*
X194298Y-115409D01*
X194698D01*
X194298Y-115009D01*
X194698Y-114609D01*
X194298D01*
X193898Y-114209D01*
X193498Y-114609D01*
X193098D01*
X193498Y-115009D01*
X193098Y-115409D01*
X193498D01*
X193898Y-115809D01*
Y-115409D02*
X194098Y-115209D01*
X194298D01*
X194098Y-115009D01*
X194298Y-114809D01*
X194098D01*
X193898Y-114609D01*
X193698Y-114809D01*
X193498D01*
X193698Y-115009D01*
X193498Y-115209D01*
X193698D01*
X193898Y-115409D01*
Y-120731D02*
X194298Y-120331D01*
X194698D01*
X194298Y-119931D01*
X194698Y-119531D01*
X194298D01*
X193898Y-119131D01*
X193498Y-119531D01*
X193098D01*
X193498Y-119931D01*
X193098Y-120331D01*
X193498D01*
X193898Y-120731D01*
Y-120331D02*
X194098Y-120131D01*
X194298D01*
X194098Y-119931D01*
X194298Y-119731D01*
X194098D01*
X193898Y-119531D01*
X193698Y-119731D01*
X193498D01*
X193698Y-119931D01*
X193498Y-120131D01*
X193698D01*
X193898Y-120331D01*
X309055Y-124668D02*
X309455Y-124268D01*
X309855D01*
X309455Y-123868D01*
X309855Y-123468D01*
X309455D01*
X309055Y-123068D01*
X308655Y-123468D01*
X308255D01*
X308655Y-123868D01*
X308255Y-124268D01*
X308655D01*
X309055Y-124668D01*
Y-124268D02*
X309255Y-124068D01*
X309455D01*
X309255Y-123868D01*
X309455Y-123668D01*
X309255D01*
X309055Y-123468D01*
X308855Y-123668D01*
X308655D01*
X308855Y-123868D01*
X308655Y-124068D01*
X308855D01*
X309055Y-124268D01*
X575332Y-125406D02*
X575732Y-124606D01*
X575332Y-123806D01*
X576132Y-124206D01*
X576932Y-123806D01*
X576532Y-124606D01*
X576932Y-125406D01*
X576132Y-125006D01*
X575332Y-125406D01*
X575732Y-125006D02*
X575932Y-124606D01*
X575732Y-124206D01*
X576132Y-124406D01*
X576532Y-124206D01*
X576332Y-124606D01*
X576532Y-125006D01*
X576132Y-124806D01*
X575732Y-125006D01*
X182677Y-387266D02*
X183077Y-386866D01*
X183477D01*
X183077Y-386466D01*
X183477Y-386066D01*
X183077D01*
X182677Y-385666D01*
X182277Y-386066D01*
X181877D01*
X182277Y-386466D01*
X181877Y-386866D01*
X182277D01*
X182677Y-387266D01*
Y-386866D02*
X182877Y-386666D01*
X183077D01*
X182877Y-386466D01*
X183077Y-386266D01*
X182877D01*
X182677Y-386066D01*
X182477Y-386266D01*
X182277D01*
X182477Y-386466D01*
X182277Y-386666D01*
X182477D01*
X182677Y-386866D01*
X186614Y-387266D02*
X187014Y-386866D01*
X187414D01*
X187014Y-386466D01*
X187414Y-386066D01*
X187014D01*
X186614Y-385666D01*
X186214Y-386066D01*
X185814D01*
X186214Y-386466D01*
X185814Y-386866D01*
X186214D01*
X186614Y-387266D01*
Y-386866D02*
X186814Y-386666D01*
X187014D01*
X186814Y-386466D01*
X187014Y-386266D01*
X186814D01*
X186614Y-386066D01*
X186414Y-386266D01*
X186214D01*
X186414Y-386466D01*
X186214Y-386666D01*
X186414D01*
X186614Y-386866D01*
X182677Y-390416D02*
X183077Y-390016D01*
X183477D01*
X183077Y-389616D01*
X183477Y-389216D01*
X183077D01*
X182677Y-388816D01*
X182277Y-389216D01*
X181877D01*
X182277Y-389616D01*
X181877Y-390016D01*
X182277D01*
X182677Y-390416D01*
Y-390016D02*
X182877Y-389816D01*
X183077D01*
X182877Y-389616D01*
X183077Y-389416D01*
X182877D01*
X182677Y-389216D01*
X182477Y-389416D01*
X182277D01*
X182477Y-389616D01*
X182277Y-389816D01*
X182477D01*
X182677Y-390016D01*
X186614Y-390416D02*
X187014Y-390016D01*
X187414D01*
X187014Y-389616D01*
X187414Y-389216D01*
X187014D01*
X186614Y-388816D01*
X186214Y-389216D01*
X185814D01*
X186214Y-389616D01*
X185814Y-390016D01*
X186214D01*
X186614Y-390416D01*
Y-390016D02*
X186814Y-389816D01*
X187014D01*
X186814Y-389616D01*
X187014Y-389416D01*
X186814D01*
X186614Y-389216D01*
X186414Y-389416D01*
X186214D01*
X186414Y-389616D01*
X186214Y-389816D01*
X186414D01*
X186614Y-390016D01*
D183*
X259272Y-327165D02*
G03*
X259272Y-327165I-800J0D01*
G01*
X283084D02*
G03*
X283084Y-327165I-800J0D01*
G01*
X294895D02*
G03*
X294895Y-327165I-800J0D01*
G01*
X303162Y-156693D02*
G03*
X303162Y-156693I-800J0D01*
G01*
Y-316535D02*
G03*
X303162Y-316535I-800J0D01*
G01*
X143320D02*
G03*
X143320Y-316535I-800J0D01*
G01*
Y-236614D02*
G03*
X143320Y-236614I-800J0D01*
G01*
Y-156693D02*
G03*
X143320Y-156693I-800J0D01*
G01*
X271272Y-327165D02*
G03*
X271272Y-327165I-800J0D01*
G01*
X247272D02*
G03*
X247272Y-327165I-800J0D01*
G01*
X641440Y-33710D02*
G03*
X641440Y-33710I-800J0D01*
G01*
Y-17962D02*
G03*
X641440Y-17962I-800J0D01*
G01*
X83586Y-53986D02*
G03*
X83586Y-53986I-800J0D01*
G01*
Y-69734D02*
G03*
X83586Y-69734I-800J0D01*
G01*
D184*
X641040Y-33710D02*
G03*
X641040Y-33710I-400J0D01*
G01*
Y-17962D02*
G03*
X641040Y-17962I-400J0D01*
G01*
X83185Y-53986D02*
G03*
X83185Y-53986I-400J0D01*
G01*
Y-69734D02*
G03*
X83185Y-69734I-400J0D01*
G01*
M02*
